FILE_TYPE = MACRO_DRAWING;
SET COLOR_WIRE YELLOW;
SET COLOR_PROP ORANGE;
SET COLOR_DOT WHITE;
SET COLOR_ARC YELLOW;
SET COLOR_BODY GREEN;
SET COLOR_NOTE PURPLE;
SET PROP_DISPLAY VALUE;
SET PAGE_NUMBER P149;
FORCEADD SN74AVC2T245RSWR..1
R 2
(-7000 2100);
FORCEPROP 1 LAST LOCATION U147
J 2
(-6750 2600);
DISPLAY 0.489362 (-6750 2600);
PAINT SKYBLUE (-6750 2600);
FORCEPROP 0 LAST $SEC 1
J 0
(-6775 2775);
PAINT MONO (-6775 2775);
DISPLAY INVISIBLE (-6775 2775);
FORCEPROP 0 LAST CDS_SEC 1
J 0
(-6775 2775);
PAINT MONO (-6775 2775);
DISPLAY INVISIBLE (-6775 2775);
FORCEPROP 0 LASTPIN (-7400 2225) $PN 8
J 2
(-7410 2235);
DISPLAY 0.489362 (-7410 2235);
PAINT MONO (-7410 2235);
FORCEPROP 0 LASTPIN (-7400 2075) $PN 9
J 2
(-7410 2085);
DISPLAY 0.489362 (-7410 2085);
PAINT MONO (-7410 2085);
FORCEPROP 0 LASTPIN (-6600 2175) $PN 5
J 0
(-6590 2185);
DISPLAY 0.489362 (-6590 2185);
PAINT MONO (-6590 2185);
FORCEPROP 0 LASTPIN (-6600 2025) $PN 4
J 0
(-6590 2035);
DISPLAY 0.489362 (-6590 2035);
PAINT MONO (-6590 2035);
FORCEPROP 0 LASTPIN (-7400 2175) $PN 10
J 2
(-7410 2185);
DISPLAY 0.489362 (-7410 2185);
PAINT MONO (-7410 2185);
FORCEPROP 0 LASTPIN (-7400 2025) $PN 1
J 2
(-7410 2035);
DISPLAY 0.489362 (-7410 2035);
PAINT MONO (-7410 2035);
FORCEPROP 0 LASTPIN (-7400 1775) $PN 3
J 2
(-7410 1785);
DISPLAY 0.489362 (-7410 1785);
PAINT MONO (-7410 1785);
FORCEPROP 0 LASTPIN (-7400 1925) $PN 2
J 2
(-7410 1935);
DISPLAY 0.489362 (-7410 1935);
PAINT MONO (-7410 1935);
FORCEPROP 0 LASTPIN (-6600 2425) $PN 7
J 0
(-6590 2435);
DISPLAY 0.489362 (-6590 2435);
PAINT MONO (-6590 2435);
FORCEPROP 0 LASTPIN (-6600 2375) $PN 6
J 0
(-6590 2385);
DISPLAY 0.489362 (-6590 2385);
PAINT MONO (-6590 2385);
FORCEPROP 2 LAST PART_TYPE SMLF
J 2
(-6750 2725);
PAINT MONO (-6750 2725);
FORCEPROP 1 LAST MATERIAL IC
J 2
(-6755 2482);
DISPLAY 0.489362 (-6755 2482);
PAINT SKYBLUE (-6755 2482);
FORCEPROP 2 LAST VALUE SN74AVC2T245RSWR
J 2
(-6750 2650);
DISPLAY 0.489362 (-6750 2650);
PAINT SKYBLUE (-6750 2650);
FORCEPROP 1 LAST PART_NUMBER AL02T245000
J 2
(-6755 2551);
DISPLAY 0.489362 (-6755 2551);
PAINT SKYBLUE (-6755 2551);
FORCEPROP 1 LAST CDS_LMAN_SYM_OUTLINE -250,375,250,-375
J 2
(-7000 2100);
DISPLAY 0.468085 (-7000 2100);
PAINT GREEN (-7000 2100);
DISPLAY INVISIBLE (-7000 2100);
FORCEPROP 2 LAST CDS_LIB pure_quanta
J 2
(-7000 2100);
PAINT MONO (-7000 2100);
DISPLAY INVISIBLE (-7000 2100);
FORCEPROP 1 LAST NEEDS_NO_SIZE TRUE
J 2
(-7250 1782);
DISPLAY 0.723404 (-7250 1782);
PAINT GREEN (-7250 1782);
DISPLAY INVISIBLE (-7250 1782);
FORCEPROP 1 LAST PATH I1
J 2
(-7250 1725);
DISPLAY 0.723404 (-7250 1725);
PAINT GREEN (-7250 1725);
DISPLAY INVISIBLE (-7250 1725);
FORCEADD Q_CAP..1
(-2650 4550);
FORCEPROP 1 LAST LOCATION C1509
J 0
(-2550 4700);
DISPLAY 0.489362 (-2550 4700);
PAINT SKYBLUE (-2550 4700);
FORCEPROP 2 LAST $SEC 1
J 0
(-2600 4750);
PAINT MONO (-2600 4750);
DISPLAY INVISIBLE (-2600 4750);
FORCEPROP 2 LAST CDS_SEC 1
J 0
(-2600 4750);
PAINT MONO (-2600 4750);
DISPLAY INVISIBLE (-2600 4750);
FORCEPROP 1 LASTPIN (-2650 4650) $PN 1
J 0
(-2640 4630);
DISPLAY 0.489362 (-2640 4630);
PAINT GREEN (-2640 4630);
FORCEPROP 1 LASTPIN (-2650 4450) $PN 2
J 0
(-2640 4430);
DISPLAY 0.489362 (-2640 4430);
PAINT GREEN (-2640 4430);
FORCEPROP 1 LAST MATERIAL X7R
J 0
(-2550 4500);
DISPLAY 0.489362 (-2550 4500);
PAINT SKYBLUE (-2550 4500);
FORCEPROP 1 LAST TOLERANCE 10%
J 0
(-2550 4550);
DISPLAY 0.489362 (-2550 4550);
PAINT SKYBLUE (-2550 4550);
FORCEPROP 1 LAST VALUE 0.1UF
J 0
(-2550 4650);
DISPLAY 0.489362 (-2550 4650);
PAINT SKYBLUE (-2550 4650);
FORCEPROP 1 LAST PART_NUMBER CH4103K1B08
J 0
(-2550 4450);
DISPLAY 0.489362 (-2550 4450);
PAINT SKYBLUE (-2550 4450);
FORCEPROP 1 LAST VOLTAGE 16V
J 0
(-2550 4600);
DISPLAY 0.489362 (-2550 4600);
PAINT SKYBLUE (-2550 4600);
FORCEPROP 1 LAST PACK_TYPE C0402
J 0
(-2550 4400);
DISPLAY 0.489362 (-2550 4400);
PAINT SKYBLUE (-2550 4400);
FORCEPROP 2 LAST CDS_LIB pure_quanta
J 0
(-2650 4550);
DISPLAY INVISIBLE (-2650 4550);
FORCEPROP 1 LAST PATH I10
J 0
(-2600 4700);
DISPLAY 0.978723 (-2600 4700);
PAINT WHITE (-2600 4700);
DISPLAY INVISIBLE (-2600 4700);
FORCEADD Q_RES..2
(-6425 3550);
FORCEPROP 1 LAST LOCATION R617
J 0
(-6325 3725);
DISPLAY 0.489362 (-6325 3725);
PAINT SKYBLUE (-6325 3725);
FORCEPROP 0 LAST $SEC 1
J 0
(-6375 3725);
DISPLAY 0.680851 (-6375 3725);
PAINT MONO (-6375 3725);
DISPLAY INVISIBLE (-6375 3725);
FORCEPROP 0 LAST CDS_SEC 1
J 0
(-6375 3725);
DISPLAY 1.021277 (-6375 3725);
DISPLAY INVISIBLE (-6375 3725);
FORCEPROP 1 LASTPIN (-6425 3650) $PN 1
J 0
(-6420 3612);
DISPLAY 0.489362 (-6420 3612);
PAINT MONO (-6420 3612);
FORCEPROP 1 LASTPIN (-6425 3450) $PN 2
J 0
(-6420 3460);
DISPLAY 0.489362 (-6420 3460);
PAINT MONO (-6420 3460);
FORCEPROP 1 LAST WATTAGE 1/16W
J 0
(-6320 3525);
DISPLAY 0.489362 (-6320 3525);
PAINT SKYBLUE (-6320 3525);
FORCEPROP 1 LAST MATERIAL CHIP
J 0
(-6325 3625);
DISPLAY 0.489362 (-6325 3625);
PAINT SKYBLUE (-6325 3625);
FORCEPROP 1 LAST TOLERANCE 5%
J 0
(-6320 3575);
DISPLAY 0.489362 (-6320 3575);
PAINT SKYBLUE (-6320 3575);
FORCEPROP 1 LAST VALUE 4.7K
J 0
(-6320 3675);
DISPLAY 0.489362 (-6320 3675);
PAINT SKYBLUE (-6320 3675);
FORCEPROP 1 LAST PART_NUMBER TMP_QCS24702JB38
J 0
(-6320 3425);
DISPLAY 0.489362 (-6320 3425);
PAINT SKYBLUE (-6320 3425);
FORCEPROP 1 LAST PACK_TYPE 0402LF
J 0
(-6320 3475);
DISPLAY 0.489362 (-6320 3475);
PAINT SKYBLUE (-6320 3475);
FORCEPROP 2 LAST CDS_LIB pure_quanta
J 0
(-6425 3550);
DISPLAY INVISIBLE (-6425 3550);
FORCEPROP 1 LAST PATH I101
J 0
(-6375 3725);
DISPLAY 0.978723 (-6375 3725);
PAINT WHITE (-6375 3725);
DISPLAY INVISIBLE (-6375 3725);
FORCEADD MOSFET_N..1
(-7525 700);
FORCEPROP 1 LAST LOCATION Q62
J 0
(-7400 745);
DISPLAY 0.489362 (-7400 745);
PAINT SKYBLUE (-7400 745);
FORCEPROP 0 LAST $SEC 1
J 0
(-7400 875);
DISPLAY 0.680851 (-7400 875);
PAINT MONO (-7400 875);
DISPLAY INVISIBLE (-7400 875);
FORCEPROP 0 LAST CDS_SEC 1
J 0
(-7400 900);
PAINT MONO (-7400 900);
DISPLAY INVISIBLE (-7400 900);
FORCEPROP 1 LASTPIN (-7475 800) $PN D
R 1
J 0
(-7475 793);
DISPLAY 0.489362 (-7475 793);
PAINT MONO (-7475 793);
FORCEPROP 1 LASTPIN (-7625 600) $PN G
J 2
(-7615 603);
DISPLAY 0.489362 (-7615 603);
PAINT MONO (-7615 603);
FORCEPROP 1 LASTPIN (-7475 500) $PN S
R 1
J 2
(-7475 513);
DISPLAY 0.489362 (-7475 513);
PAINT MONO (-7475 513);
FORCEPROP 1 LAST MATERIAL IC
J 0
(-7400 585);
DISPLAY 0.489362 (-7400 585);
PAINT SKYBLUE (-7400 585);
FORCEPROP 1 LAST VALUE BSS138K
J 0
(-7400 825);
DISPLAY 0.489362 (-7400 825);
PAINT SKYBLUE (-7400 825);
FORCEPROP 1 LAST PART_NUMBER BAM138K0000
J 0
(-7400 665);
DISPLAY 0.489362 (-7400 665);
PAINT SKYBLUE (-7400 665);
FORCEPROP 2 LAST PART_TYPE SMLF
J 0
(-7675 825);
PAINT MONO (-7675 825);
FORCEPROP 0 LAST MANUF_PN BSS138K
J 0
(-7850 950);
DISPLAY 1.021277 (-7850 950);
DISPLAY INVISIBLE (-7850 950);
FORCEPROP 2 LAST CDS_LIB pure_quanta
J 0
(-7525 700);
DISPLAY INVISIBLE (-7525 700);
FORCEPROP 1 LAST CDS_LMAN_SYM_OUTLINE -50,50,100,-150
J 0
(-7525 700);
DISPLAY 0.468085 (-7525 700);
PAINT GREEN (-7525 700);
DISPLAY INVISIBLE (-7525 700);
FORCEPROP 0 LAST PATH I102
J 0
(-7850 900);
DISPLAY 1.021277 (-7850 900);
DISPLAY INVISIBLE (-7850 900);
FORCEPROP 1 LAST PACK_TYPE SMLF
J 0
(-7500 450);
DISPLAY 0.723404 (-7500 450);
PAINT SKYBLUE (-7500 450);
DISPLAY INVISIBLE (-7500 450);
FORCEADD Q_RES..1
(-3975 5850);
FORCEPROP 1 LAST LOCATION R1354
J 0
(-4175 5850);
DISPLAY 0.489362 (-4175 5850);
PAINT SKYBLUE (-4175 5850);
FORCEPROP 0 LAST $SEC 1
J 0
(-4100 5900);
DISPLAY 0.680851 (-4100 5900);
PAINT MONO (-4100 5900);
DISPLAY INVISIBLE (-4100 5900);
FORCEPROP 0 LAST CDS_SEC 1
J 0
(-4100 5900);
DISPLAY 0.680851 (-4100 5900);
DISPLAY INVISIBLE (-4100 5900);
FORCEPROP 1 LASTPIN (-4075 5850) $PN 1
J 0
(-4063 5862);
DISPLAY 0.489362 (-4063 5862);
PAINT MONO (-4063 5862);
FORCEPROP 1 LASTPIN (-3875 5850) $PN 2
J 0
(-3913 5862);
DISPLAY 0.489362 (-3913 5862);
PAINT MONO (-3913 5862);
FORCEPROP 1 LAST VALUE 0
J 2
(-3825 5850);
DISPLAY 0.489362 (-3825 5850);
PAINT SKYBLUE (-3825 5850);
FORCEPROP 2 LAST CDS_LIB pure_quanta
J 0
(-3975 5850);
DISPLAY INVISIBLE (-3975 5850);
FORCEPROP 1 LAST PATH I109
J 0
(-4025 6000);
DISPLAY 0.978723 (-4025 6000);
PAINT WHITE (-4025 6000);
DISPLAY INVISIBLE (-4025 6000);
FORCEPROP 1 LAST WATTAGE 1/16W
J 2
(-4000 5700);
DISPLAY 0.978723 (-4000 5700);
PAINT SKYBLUE (-4000 5700);
DISPLAY INVISIBLE (-4000 5700);
FORCEPROP 1 LAST MATERIAL CHIP
J 0
(-3750 5850);
DISPLAY 0.617021 (-3750 5850);
PAINT SKYBLUE (-3750 5850);
DISPLAY INVISIBLE (-3750 5850);
FORCEPROP 1 LAST TOLERANCE 5%
J 0
(-3975 5750);
DISPLAY 0.978723 (-3975 5750);
PAINT SKYBLUE (-3975 5750);
DISPLAY INVISIBLE (-3975 5750);
FORCEPROP 1 LAST PART_NUMBER CS00002JB38
J 0
(-4025 5950);
DISPLAY 0.978723 (-4025 5950);
PAINT SKYBLUE (-4025 5950);
DISPLAY INVISIBLE (-4025 5950);
FORCEPROP 1 LAST PACK_TYPE 0402LF
J 0
(-3725 5700);
DISPLAY 0.978723 (-3725 5700);
PAINT SKYBLUE (-3725 5700);
DISPLAY INVISIBLE (-3725 5700);
FORCEADD GND..1
(-2650 4375);
FORCEPROP 3 LASTPIN (-2650 4425) SIG_NAME GND\g
J 0
(-2640 4435);
DISPLAY 0.659574 (-2640 4435);
PAINT MONO (-2640 4435);
DISPLAY INVISIBLE (-2640 4435);
FORCEPROP 2 LAST CDS_LIB pure_quanta_power
J 0
(-2650 4375);
DISPLAY INVISIBLE (-2650 4375);
FORCEPROP 1 LAST SIZE 1B
J 0
(-2575 4325);
DISPLAY 0.872340 (-2575 4325);
PAINT GREEN (-2575 4325);
DISPLAY INVISIBLE (-2575 4325);
FORCEPROP 1 LAST PATH I11
J 0
(-2575 4375);
DISPLAY 0.872340 (-2575 4375);
PAINT AQUA (-2575 4375);
DISPLAY INVISIBLE (-2575 4375);
FORCEPROP 1 LAST HDL_POWER GND
J 0
(-2650 4525);
DISPLAY 0.872340 (-2650 4525);
PAINT GREEN (-2650 4525);
DISPLAY INVISIBLE (-2650 4525);
FORCEADD GND..1
(-3675 5100);
FORCEPROP 3 LASTPIN (-3675 5150) SIG_NAME GND\g
J 0
(-3665 5160);
DISPLAY 0.659574 (-3665 5160);
PAINT MONO (-3665 5160);
DISPLAY INVISIBLE (-3665 5160);
FORCEPROP 1 LAST SIZE 1B
J 0
(-3600 5050);
DISPLAY 0.872340 (-3600 5050);
PAINT GREEN (-3600 5050);
DISPLAY INVISIBLE (-3600 5050);
FORCEPROP 2 LAST CDS_LIB pure_quanta_power
J 0
(-3675 5100);
DISPLAY INVISIBLE (-3675 5100);
FORCEPROP 1 LAST PATH I110
J 0
(-3600 5100);
DISPLAY 0.872340 (-3600 5100);
PAINT AQUA (-3600 5100);
DISPLAY INVISIBLE (-3600 5100);
FORCEPROP 1 LAST HDL_POWER GND
J 0
(-3675 5250);
DISPLAY 0.872340 (-3675 5250);
PAINT GREEN (-3675 5250);
DISPLAY INVISIBLE (-3675 5250);
FORCEADD Q_RES..2
(-3650 6125);
FORCEPROP 1 LAST LOCATION R1624
J 0
(-3625 6225);
DISPLAY 0.489362 (-3625 6225);
PAINT SKYBLUE (-3625 6225);
FORCEPROP 2 LAST $SEC 1
J 0
(-3600 6350);
DISPLAY 0.680851 (-3600 6350);
PAINT MONO (-3600 6350);
DISPLAY INVISIBLE (-3600 6350);
FORCEPROP 2 LAST CDS_SEC 1
J 0
(-3600 6350);
DISPLAY 1.021277 (-3600 6350);
DISPLAY INVISIBLE (-3600 6350);
FORCEPROP 1 LASTPIN (-3650 6225) $PN 1
J 0
(-3645 6187);
DISPLAY 0.489362 (-3645 6187);
FORCEPROP 1 LASTPIN (-3650 6025) $PN 2
J 0
(-3645 6035);
DISPLAY 0.489362 (-3645 6035);
FORCEPROP 1 LAST TOLERANCE 5%
J 0
(-3625 6125);
DISPLAY 0.489362 (-3625 6125);
PAINT SKYBLUE (-3625 6125);
FORCEPROP 1 LAST VALUE 1K
J 0
(-3625 6175);
DISPLAY 0.489362 (-3625 6175);
PAINT SKYBLUE (-3625 6175);
FORCEPROP 2 LAST CDS_LIB pure_quanta
J 0
(-3650 6125);
DISPLAY INVISIBLE (-3650 6125);
FORCEPROP 1 LAST PATH I111
J 0
(-3600 6300);
DISPLAY 0.978723 (-3600 6300);
PAINT WHITE (-3600 6300);
DISPLAY INVISIBLE (-3600 6300);
FORCEPROP 1 LAST WATTAGE 1/16W
J 0
(-3625 6075);
DISPLAY 0.489362 (-3625 6075);
PAINT SKYBLUE (-3625 6075);
DISPLAY INVISIBLE (-3625 6075);
FORCEPROP 1 LAST MATERIAL CHIP
J 0
(-3625 6025);
DISPLAY 0.489362 (-3625 6025);
PAINT SKYBLUE (-3625 6025);
DISPLAY INVISIBLE (-3625 6025);
FORCEPROP 1 LAST PART_NUMBER TMP_QCS21002JB34
J 0
(-3610 6000);
DISPLAY 0.617021 (-3610 6000);
PAINT SKYBLUE (-3610 6000);
DISPLAY INVISIBLE (-3610 6000);
FORCEPROP 1 LAST PACK_TYPE 0402LF
J 0
(-3625 5975);
DISPLAY 0.489362 (-3625 5975);
PAINT SKYBLUE (-3625 5975);
DISPLAY INVISIBLE (-3625 5975);
FORCEADD Q_RES..2
(-3675 5325);
FORCEPROP 1 LAST LOCATION R1629
J 0
(-3600 5375);
DISPLAY 0.489362 (-3600 5375);
PAINT SKYBLUE (-3600 5375);
FORCEPROP 0 LAST $SEC 1
J 0
(-3550 5550);
PAINT MONO (-3550 5550);
DISPLAY INVISIBLE (-3550 5550);
FORCEPROP 0 LAST CDS_SEC 1
J 0
(-3550 5550);
PAINT MONO (-3550 5550);
DISPLAY INVISIBLE (-3550 5550);
FORCEPROP 1 LASTPIN (-3675 5425) $PN 1
J 0
(-3670 5387);
DISPLAY 0.489362 (-3670 5387);
PAINT GREEN (-3670 5387);
FORCEPROP 1 LASTPIN (-3675 5225) $PN 2
J 0
(-3670 5235);
DISPLAY 0.489362 (-3670 5235);
PAINT GREEN (-3670 5235);
FORCEPROP 1 LAST WATTAGE 1/16W
J 0
(-3600 5275);
DISPLAY 0.489362 (-3600 5275);
PAINT SKYBLUE (-3600 5275);
FORCEPROP 1 LAST MATERIAL CHIP
J 0
(-3600 5325);
DISPLAY 0.489362 (-3600 5325);
PAINT SKYBLUE (-3600 5325);
FORCEPROP 1 LAST TOLERANCE 5%
J 0
(-3600 5300);
DISPLAY 0.489362 (-3600 5300);
PAINT SKYBLUE (-3600 5300);
FORCEPROP 1 LAST VALUE 1K
J 0
(-3600 5350);
DISPLAY 0.489362 (-3600 5350);
PAINT SKYBLUE (-3600 5350);
FORCEPROP 1 LAST PART_NUMBER TMP_QCS21002JB34
J 0
(-3600 5225);
DISPLAY 0.489362 (-3600 5225);
PAINT SKYBLUE (-3600 5225);
FORCEPROP 1 LAST PACK_TYPE 0402LF
J 0
(-3600 5250);
DISPLAY 0.489362 (-3600 5250);
PAINT SKYBLUE (-3600 5250);
FORCEPROP 2 LAST CDS_LIB pure_quanta
J 0
(-3675 5325);
PAINT MONO (-3675 5325);
DISPLAY INVISIBLE (-3675 5325);
FORCEPROP 1 LAST PATH I112
J 0
(-3625 5500);
DISPLAY 0.978723 (-3625 5500);
PAINT WHITE (-3625 5500);
DISPLAY INVISIBLE (-3625 5500);
FORCEADD Q_RES..1
(-3025 5600);
FORCEPROP 1 LAST LOCATION R1631
J 0
(-3250 5600);
DISPLAY 0.489362 (-3250 5600);
PAINT SKYBLUE (-3250 5600);
FORCEPROP 2 LAST $SEC 1
J 0
(-3075 5800);
DISPLAY 0.680851 (-3075 5800);
PAINT MONO (-3075 5800);
DISPLAY INVISIBLE (-3075 5800);
FORCEPROP 2 LAST CDS_SEC 1
J 0
(-3075 5800);
DISPLAY 1.021277 (-3075 5800);
DISPLAY INVISIBLE (-3075 5800);
FORCEPROP 1 LASTPIN (-3125 5600) $PN 1
J 0
(-3113 5612);
DISPLAY 0.489362 (-3113 5612);
FORCEPROP 1 LASTPIN (-2925 5600) $PN 2
J 0
(-2963 5612);
DISPLAY 0.489362 (-2963 5612);
FORCEPROP 1 LAST VALUE 33
J 2
(-2850 5600);
DISPLAY 0.489362 (-2850 5600);
PAINT SKYBLUE (-2850 5600);
FORCEPROP 2 LAST CDS_LIB pure_quanta
J 0
(-3025 5600);
DISPLAY INVISIBLE (-3025 5600);
FORCEPROP 1 LAST PATH I113
J 0
(-3075 5750);
DISPLAY 0.978723 (-3075 5750);
PAINT WHITE (-3075 5750);
DISPLAY INVISIBLE (-3075 5750);
FORCEPROP 1 LAST WATTAGE 1/16W
J 2
(-3050 5450);
DISPLAY 0.978723 (-3050 5450);
PAINT SKYBLUE (-3050 5450);
DISPLAY INVISIBLE (-3050 5450);
FORCEPROP 1 LAST MATERIAL CHIP
J 0
(-2800 5600);
DISPLAY 0.489362 (-2800 5600);
PAINT SKYBLUE (-2800 5600);
DISPLAY INVISIBLE (-2800 5600);
FORCEPROP 1 LAST TOLERANCE 5%
J 0
(-3025 5500);
DISPLAY 0.978723 (-3025 5500);
PAINT SKYBLUE (-3025 5500);
DISPLAY INVISIBLE (-3025 5500);
FORCEPROP 1 LAST PART_NUMBER CS03302JB29
J 0
(-3075 5700);
DISPLAY 0.978723 (-3075 5700);
PAINT SKYBLUE (-3075 5700);
DISPLAY INVISIBLE (-3075 5700);
FORCEPROP 1 LAST PACK_TYPE 0402LF
J 0
(-2950 5550);
DISPLAY 0.489362 (-2950 5550);
PAINT SKYBLUE (-2950 5550);
DISPLAY INVISIBLE (-2950 5550);
FORCEADD Q_RES..1
(-3025 5550);
FORCEPROP 1 LAST LOCATION R1632
J 0
(-3250 5550);
DISPLAY 0.489362 (-3250 5550);
PAINT SKYBLUE (-3250 5550);
FORCEPROP 2 LAST $SEC 1
J 0
(-3075 5750);
DISPLAY 0.680851 (-3075 5750);
PAINT MONO (-3075 5750);
DISPLAY INVISIBLE (-3075 5750);
FORCEPROP 2 LAST CDS_SEC 1
J 0
(-3075 5750);
DISPLAY 1.021277 (-3075 5750);
DISPLAY INVISIBLE (-3075 5750);
FORCEPROP 1 LASTPIN (-3125 5550) $PN 1
J 0
(-3113 5562);
DISPLAY 0.489362 (-3113 5562);
FORCEPROP 1 LASTPIN (-2925 5550) $PN 2
J 0
(-2963 5562);
DISPLAY 0.489362 (-2963 5562);
FORCEPROP 1 LAST VALUE 33
J 2
(-2850 5550);
DISPLAY 0.489362 (-2850 5550);
PAINT SKYBLUE (-2850 5550);
FORCEPROP 2 LAST CDS_LIB pure_quanta
J 0
(-3025 5550);
DISPLAY INVISIBLE (-3025 5550);
FORCEPROP 1 LAST PATH I114
J 0
(-3075 5700);
DISPLAY 0.978723 (-3075 5700);
PAINT WHITE (-3075 5700);
DISPLAY INVISIBLE (-3075 5700);
FORCEPROP 1 LAST WATTAGE 1/16W
J 2
(-3050 5400);
DISPLAY 0.978723 (-3050 5400);
PAINT SKYBLUE (-3050 5400);
DISPLAY INVISIBLE (-3050 5400);
FORCEPROP 1 LAST MATERIAL CHIP
J 0
(-3075 5500);
DISPLAY 0.489362 (-3075 5500);
PAINT SKYBLUE (-3075 5500);
DISPLAY INVISIBLE (-3075 5500);
FORCEPROP 1 LAST TOLERANCE 5%
J 0
(-3025 5450);
DISPLAY 0.978723 (-3025 5450);
PAINT SKYBLUE (-3025 5450);
DISPLAY INVISIBLE (-3025 5450);
FORCEPROP 1 LAST PART_NUMBER CS03302JB29
J 0
(-3075 5650);
DISPLAY 0.978723 (-3075 5650);
PAINT SKYBLUE (-3075 5650);
DISPLAY INVISIBLE (-3075 5650);
FORCEPROP 1 LAST PACK_TYPE 0402LF
J 0
(-2950 5500);
DISPLAY 0.489362 (-2950 5500);
PAINT SKYBLUE (-2950 5500);
DISPLAY INVISIBLE (-2950 5500);
FORCEADD Q_RES..2
(-3525 6125);
FORCEPROP 1 LAST LOCATION R1626
J 0
(-3500 6225);
DISPLAY 0.489362 (-3500 6225);
PAINT SKYBLUE (-3500 6225);
FORCEPROP 2 LAST $SEC 1
J 0
(-3475 6350);
DISPLAY 0.680851 (-3475 6350);
PAINT MONO (-3475 6350);
DISPLAY INVISIBLE (-3475 6350);
FORCEPROP 2 LAST CDS_SEC 1
J 0
(-3475 6350);
DISPLAY 1.021277 (-3475 6350);
DISPLAY INVISIBLE (-3475 6350);
FORCEPROP 1 LASTPIN (-3525 6225) $PN 1
J 0
(-3520 6187);
DISPLAY 0.489362 (-3520 6187);
FORCEPROP 1 LASTPIN (-3525 6025) $PN 2
J 0
(-3520 6035);
DISPLAY 0.489362 (-3520 6035);
FORCEPROP 1 LAST TOLERANCE 5%
J 0
(-3500 6125);
DISPLAY 0.489362 (-3500 6125);
PAINT SKYBLUE (-3500 6125);
FORCEPROP 1 LAST VALUE 1K
J 0
(-3500 6175);
DISPLAY 0.489362 (-3500 6175);
PAINT SKYBLUE (-3500 6175);
FORCEPROP 2 LAST CDS_LIB pure_quanta
J 0
(-3525 6125);
DISPLAY INVISIBLE (-3525 6125);
FORCEPROP 1 LAST PATH I115
J 0
(-3475 6300);
DISPLAY 0.978723 (-3475 6300);
PAINT WHITE (-3475 6300);
DISPLAY INVISIBLE (-3475 6300);
FORCEPROP 1 LAST WATTAGE 1/16W
J 0
(-3500 6075);
DISPLAY 0.489362 (-3500 6075);
PAINT SKYBLUE (-3500 6075);
DISPLAY INVISIBLE (-3500 6075);
FORCEPROP 1 LAST MATERIAL CHIP
J 0
(-3500 6025);
DISPLAY 0.489362 (-3500 6025);
PAINT SKYBLUE (-3500 6025);
DISPLAY INVISIBLE (-3500 6025);
FORCEPROP 1 LAST PART_NUMBER TMP_QCS21002JB34
J 0
(-3485 6000);
DISPLAY 0.617021 (-3485 6000);
PAINT SKYBLUE (-3485 6000);
DISPLAY INVISIBLE (-3485 6000);
FORCEPROP 1 LAST PACK_TYPE 0402LF
J 0
(-3500 5975);
DISPLAY 0.489362 (-3500 5975);
PAINT SKYBLUE (-3500 5975);
DISPLAY INVISIBLE (-3500 5975);
FORCEADD Q_RES..2
(-3400 6125);
FORCEPROP 1 LAST LOCATION R1627
J 0
(-3375 6225);
DISPLAY 0.489362 (-3375 6225);
PAINT SKYBLUE (-3375 6225);
FORCEPROP 2 LAST $SEC 1
J 0
(-3350 6350);
DISPLAY 0.680851 (-3350 6350);
PAINT MONO (-3350 6350);
DISPLAY INVISIBLE (-3350 6350);
FORCEPROP 2 LAST CDS_SEC 1
J 0
(-3350 6350);
DISPLAY 1.021277 (-3350 6350);
DISPLAY INVISIBLE (-3350 6350);
FORCEPROP 1 LASTPIN (-3400 6225) $PN 1
J 0
(-3395 6187);
DISPLAY 0.489362 (-3395 6187);
FORCEPROP 1 LASTPIN (-3400 6025) $PN 2
J 0
(-3395 6035);
DISPLAY 0.489362 (-3395 6035);
FORCEPROP 1 LAST VALUE 1K
J 0
(-3375 6175);
DISPLAY 0.489362 (-3375 6175);
PAINT SKYBLUE (-3375 6175);
FORCEPROP 1 LAST TOLERANCE 5%
J 0
(-3375 6125);
DISPLAY 0.489362 (-3375 6125);
PAINT SKYBLUE (-3375 6125);
FORCEPROP 2 LAST CDS_LIB pure_quanta
J 0
(-3400 6125);
DISPLAY INVISIBLE (-3400 6125);
FORCEPROP 1 LAST PATH I116
J 0
(-3350 6300);
DISPLAY 0.978723 (-3350 6300);
PAINT WHITE (-3350 6300);
DISPLAY INVISIBLE (-3350 6300);
FORCEPROP 1 LAST WATTAGE 1/16W
J 0
(-3375 6075);
DISPLAY 0.489362 (-3375 6075);
PAINT SKYBLUE (-3375 6075);
DISPLAY INVISIBLE (-3375 6075);
FORCEPROP 1 LAST MATERIAL CHIP
J 0
(-3375 6025);
DISPLAY 0.489362 (-3375 6025);
PAINT SKYBLUE (-3375 6025);
DISPLAY INVISIBLE (-3375 6025);
FORCEPROP 1 LAST PART_NUMBER TMP_QCS21002JB34
J 0
(-3360 6000);
DISPLAY 0.617021 (-3360 6000);
PAINT SKYBLUE (-3360 6000);
DISPLAY INVISIBLE (-3360 6000);
FORCEPROP 1 LAST PACK_TYPE 0402LF
J 0
(-3375 5975);
DISPLAY 0.489362 (-3375 5975);
PAINT SKYBLUE (-3375 5975);
DISPLAY INVISIBLE (-3375 5975);
FORCEADD Q_RES..2
(-3275 6125);
FORCEPROP 1 LAST LOCATION R1628
J 0
(-3250 6225);
DISPLAY 0.489362 (-3250 6225);
PAINT SKYBLUE (-3250 6225);
FORCEPROP 2 LAST $SEC 1
J 0
(-3225 6350);
DISPLAY 0.680851 (-3225 6350);
PAINT MONO (-3225 6350);
DISPLAY INVISIBLE (-3225 6350);
FORCEPROP 2 LAST CDS_SEC 1
J 0
(-3225 6350);
DISPLAY 1.021277 (-3225 6350);
DISPLAY INVISIBLE (-3225 6350);
FORCEPROP 1 LASTPIN (-3275 6225) $PN 1
J 0
(-3270 6187);
DISPLAY 0.489362 (-3270 6187);
FORCEPROP 1 LASTPIN (-3275 6025) $PN 2
J 0
(-3270 6035);
DISPLAY 0.489362 (-3270 6035);
FORCEPROP 1 LAST TOLERANCE 5%
J 0
(-3250 6125);
DISPLAY 0.489362 (-3250 6125);
PAINT SKYBLUE (-3250 6125);
FORCEPROP 1 LAST VALUE 1K
J 0
(-3250 6175);
DISPLAY 0.489362 (-3250 6175);
PAINT SKYBLUE (-3250 6175);
FORCEPROP 2 LAST CDS_LIB pure_quanta
J 0
(-3275 6125);
DISPLAY INVISIBLE (-3275 6125);
FORCEPROP 1 LAST PATH I117
J 0
(-3225 6300);
DISPLAY 0.978723 (-3225 6300);
PAINT WHITE (-3225 6300);
DISPLAY INVISIBLE (-3225 6300);
FORCEPROP 1 LAST WATTAGE 1/16W
J 0
(-3250 6075);
DISPLAY 0.489362 (-3250 6075);
PAINT SKYBLUE (-3250 6075);
DISPLAY INVISIBLE (-3250 6075);
FORCEPROP 1 LAST MATERIAL CHIP
J 0
(-3250 6025);
DISPLAY 0.489362 (-3250 6025);
PAINT SKYBLUE (-3250 6025);
DISPLAY INVISIBLE (-3250 6025);
FORCEPROP 1 LAST PART_NUMBER TMP_QCS21002JB34
J 0
(-3235 6000);
DISPLAY 0.617021 (-3235 6000);
PAINT SKYBLUE (-3235 6000);
DISPLAY INVISIBLE (-3235 6000);
FORCEPROP 1 LAST PACK_TYPE 0402LF
J 0
(-3250 5975);
DISPLAY 0.489362 (-3250 5975);
PAINT SKYBLUE (-3250 5975);
DISPLAY INVISIBLE (-3250 5975);
FORCEADD Q_RES..2
(-3150 6125);
FORCEPROP 1 LAST LOCATION R1630
J 0
(-3125 6225);
DISPLAY 0.489362 (-3125 6225);
PAINT SKYBLUE (-3125 6225);
FORCEPROP 2 LAST $SEC 1
J 0
(-3100 6350);
DISPLAY 0.680851 (-3100 6350);
PAINT MONO (-3100 6350);
DISPLAY INVISIBLE (-3100 6350);
FORCEPROP 2 LAST CDS_SEC 1
J 0
(-3100 6350);
DISPLAY 1.021277 (-3100 6350);
DISPLAY INVISIBLE (-3100 6350);
FORCEPROP 1 LASTPIN (-3150 6225) $PN 1
J 0
(-3145 6187);
DISPLAY 0.489362 (-3145 6187);
FORCEPROP 1 LASTPIN (-3150 6025) $PN 2
J 0
(-3145 6035);
DISPLAY 0.489362 (-3145 6035);
FORCEPROP 1 LAST TOLERANCE 5%
J 0
(-3125 6125);
DISPLAY 0.489362 (-3125 6125);
PAINT SKYBLUE (-3125 6125);
FORCEPROP 1 LAST VALUE 1K
J 0
(-3125 6175);
DISPLAY 0.489362 (-3125 6175);
PAINT SKYBLUE (-3125 6175);
FORCEPROP 2 LAST CDS_LIB pure_quanta
J 0
(-3150 6125);
DISPLAY INVISIBLE (-3150 6125);
FORCEPROP 1 LAST PATH I118
J 0
(-3100 6300);
DISPLAY 0.978723 (-3100 6300);
PAINT WHITE (-3100 6300);
DISPLAY INVISIBLE (-3100 6300);
FORCEPROP 1 LAST WATTAGE 1/16W
J 0
(-3125 6075);
DISPLAY 0.489362 (-3125 6075);
PAINT SKYBLUE (-3125 6075);
DISPLAY INVISIBLE (-3125 6075);
FORCEPROP 1 LAST MATERIAL CHIP
J 0
(-3125 6025);
DISPLAY 0.489362 (-3125 6025);
PAINT SKYBLUE (-3125 6025);
DISPLAY INVISIBLE (-3125 6025);
FORCEPROP 1 LAST PART_NUMBER TMP_QCS21002JB34
J 0
(-3110 6000);
DISPLAY 0.617021 (-3110 6000);
PAINT SKYBLUE (-3110 6000);
DISPLAY INVISIBLE (-3110 6000);
FORCEPROP 1 LAST PACK_TYPE 0402LF
J 0
(-3125 5975);
DISPLAY 0.489362 (-3125 5975);
PAINT SKYBLUE (-3125 5975);
DISPLAY INVISIBLE (-3125 5975);
FORCEADD UNIVERSAL_POWER..1
(-3650 6400);
FORCEPROP 3 LASTPIN (-3650 6350) SIG_NAME PVDD18_S5_P0\g
J 0
(-3640 6360);
DISPLAY 0.659574 (-3640 6360);
PAINT MONO (-3640 6360);
DISPLAY INVISIBLE (-3640 6360);
FORCEPROP 1 LAST HDL_POWER PVDD18_S5_P0
J 1
(-3550 6450);
DISPLAY 0.489362 (-3550 6450);
PAINT GREEN (-3550 6450);
FORCEPROP 2 LAST CDS_LIB pure_quanta_power
J 0
(-3650 6400);
DISPLAY INVISIBLE (-3650 6400);
FORCEPROP 1 LAST PATH I119
J 0
(-3600 6425);
DISPLAY 0.872340 (-3600 6425);
PAINT AQUA (-3600 6425);
DISPLAY INVISIBLE (-3600 6425);
FORCEADD UNIVERSAL_POWER..1
(-2725 4850);
FORCEPROP 3 LASTPIN (-2725 4800) SIG_NAME PVDD18_S5_P0\g
J 0
(-2715 4810);
DISPLAY 0.659574 (-2715 4810);
PAINT MONO (-2715 4810);
DISPLAY INVISIBLE (-2715 4810);
FORCEPROP 1 LAST HDL_POWER PVDD18_S5_P0
J 1
(-2725 4900);
DISPLAY 0.489362 (-2725 4900);
PAINT GREEN (-2725 4900);
FORCEPROP 2 LAST CDS_LIB pure_quanta_power
J 0
(-2725 4850);
PAINT MONO (-2725 4850);
DISPLAY INVISIBLE (-2725 4850);
FORCEPROP 1 LAST PATH I12
J 0
(-2675 4875);
DISPLAY 0.872340 (-2675 4875);
PAINT AQUA (-2675 4875);
DISPLAY INVISIBLE (-2675 4875);
FORCEADD GND..1
(-2350 5100);
FORCEPROP 3 LASTPIN (-2350 5150) SIG_NAME GND\g
J 0
(-2340 5160);
DISPLAY 0.659574 (-2340 5160);
PAINT MONO (-2340 5160);
DISPLAY INVISIBLE (-2340 5160);
FORCEPROP 1 LAST SIZE 1B
J 0
(-2275 5050);
DISPLAY 0.872340 (-2275 5050);
PAINT GREEN (-2275 5050);
DISPLAY INVISIBLE (-2275 5050);
FORCEPROP 2 LAST CDS_LIB pure_quanta_power
J 0
(-2350 5100);
DISPLAY INVISIBLE (-2350 5100);
FORCEPROP 1 LAST PATH I120
J 0
(-2275 5100);
DISPLAY 0.872340 (-2275 5100);
PAINT AQUA (-2275 5100);
DISPLAY INVISIBLE (-2275 5100);
FORCEPROP 1 LAST HDL_POWER GND
J 0
(-2350 5250);
DISPLAY 0.872340 (-2350 5250);
PAINT GREEN (-2350 5250);
DISPLAY INVISIBLE (-2350 5250);
FORCEADD GND..1
(-2125 5100);
FORCEPROP 3 LASTPIN (-2125 5150) SIG_NAME GND\g
J 0
(-2115 5160);
DISPLAY 0.659574 (-2115 5160);
PAINT MONO (-2115 5160);
DISPLAY INVISIBLE (-2115 5160);
FORCEPROP 2 LAST CDS_LIB pure_quanta_power
J 0
(-2125 5100);
DISPLAY INVISIBLE (-2125 5100);
FORCEPROP 1 LAST SIZE 1B
J 0
(-2050 5050);
DISPLAY 0.872340 (-2050 5050);
PAINT GREEN (-2050 5050);
DISPLAY INVISIBLE (-2050 5050);
FORCEPROP 1 LAST PATH I121
J 0
(-2050 5100);
DISPLAY 0.872340 (-2050 5100);
PAINT AQUA (-2050 5100);
DISPLAY INVISIBLE (-2050 5100);
FORCEPROP 1 LAST HDL_POWER GND
J 0
(-2125 5250);
DISPLAY 0.872340 (-2125 5250);
PAINT GREEN (-2125 5250);
DISPLAY INVISIBLE (-2125 5250);
FORCEADD Q_CAP..1
(-2125 5325);
FORCEPROP 1 LAST LOCATION C551
J 0
(-2075 5425);
DISPLAY 0.489362 (-2075 5425);
PAINT SKYBLUE (-2075 5425);
FORCEPROP 2 LAST $SEC 1
J 0
(-2075 5525);
DISPLAY 0.680851 (-2075 5525);
PAINT MONO (-2075 5525);
DISPLAY INVISIBLE (-2075 5525);
FORCEPROP 2 LAST CDS_SEC 1
J 0
(-2075 5525);
DISPLAY 1.021277 (-2075 5525);
DISPLAY INVISIBLE (-2075 5525);
FORCEPROP 1 LASTPIN (-2125 5425) $PN 1
J 0
(-2115 5405);
DISPLAY 0.489362 (-2115 5405);
FORCEPROP 1 LASTPIN (-2125 5225) $PN 2
J 0
(-2115 5205);
DISPLAY 0.489362 (-2115 5205);
FORCEPROP 1 LAST MATERIAL X7R
J 0
(-2075 5225);
DISPLAY 0.489362 (-2075 5225);
PAINT SKYBLUE (-2075 5225);
FORCEPROP 1 LAST TOLERANCE 10%
J 0
(-2075 5275);
DISPLAY 0.489362 (-2075 5275);
PAINT SKYBLUE (-2075 5275);
FORCEPROP 1 LAST VALUE 0.01UF
J 0
(-2075 5375);
DISPLAY 0.489362 (-2075 5375);
PAINT SKYBLUE (-2075 5375);
FORCEPROP 1 LAST VOLTAGE 50V
J 0
(-2075 5325);
DISPLAY 0.489362 (-2075 5325);
PAINT SKYBLUE (-2075 5325);
FORCEPROP 1 LAST PACK_TYPE C0402
J 0
(-2075 5175);
DISPLAY 0.489362 (-2075 5175);
PAINT SKYBLUE (-2075 5175);
FORCEPROP 2 LAST SIGNAL_MODEL DEFAULT_CAPACITOR_10000PF_2_1
J 0
(-2075 5525);
DISPLAY 0.808511 (-2075 5525);
PAINT MONO (-2075 5525);
DISPLAY INVISIBLE (-2075 5525);
FORCEPROP 2 LAST CDS_LIB pure_quanta
J 0
(-2125 5325);
DISPLAY INVISIBLE (-2125 5325);
FORCEPROP 1 LAST PATH I123
J 0
(-2075 5475);
DISPLAY 0.978723 (-2075 5475);
PAINT WHITE (-2075 5475);
DISPLAY INVISIBLE (-2075 5475);
FORCEPROP 1 LAST PART_NUMBER CH31006KB18
R 1
J 0
(-2175 5075);
DISPLAY 0.617021 (-2175 5075);
PAINT SKYBLUE (-2175 5075);
DISPLAY INVISIBLE (-2175 5075);
FORCEPROP 2 LAST ROOM BMCLESS
J 0
(-2075 5475);
DISPLAY 1.148936 (-2075 5475);
PAINT RED (-2075 5475);
DISPLAY INVISIBLE (-2075 5475);
FORCEADD OFFPAGE..2
(-1625 5600);
FORCEPROP 2 LAST $XR0 149 
J 0
(-1436 5600);
DISPLAY 0.638298 (-1436 5600);
PAINT MONO (-1436 5600);
FORCEPROP 2 LAST PATH I124
J 0
(-1425 5650);
DISPLAY 0.680851 (-1425 5650);
DISPLAY INVISIBLE (-1425 5650);
FORCEPROP 1 LAST COMMENT_BODY TRUE
J 0
(-1670 5505);
DISPLAY 0.872340 (-1670 5505);
PAINT GREEN (-1670 5505);
DISPLAY INVISIBLE (-1670 5505);
FORCEPROP 1 LAST OFFPAGE TRUE
J 0
(-1300 5475);
DISPLAY 0.872340 (-1300 5475);
PAINT GREEN (-1300 5475);
DISPLAY INVISIBLE (-1300 5475);
FORCEPROP 2 LAST CDS_LIB standard
J 0
(-1625 5600);
DISPLAY INVISIBLE (-1625 5600);
FORCEADD OFFPAGE..1
R 2
(-1650 5700);
FORCEPROP 2 LAST $XR0 80 
J 0
(-1464 5700);
DISPLAY 0.638298 (-1464 5700);
PAINT MONO (-1464 5700);
FORCEPROP 2 LAST PATH I125
J 0
(-1450 5750);
DISPLAY 0.680851 (-1450 5750);
DISPLAY INVISIBLE (-1450 5750);
FORCEPROP 1 LAST COMMENT_BODY TRUE
J 2
(-1775 5600);
DISPLAY 0.872340 (-1775 5600);
PAINT GREEN (-1775 5600);
DISPLAY INVISIBLE (-1775 5600);
FORCEPROP 1 LAST OFFPAGE TRUE
J 2
(-1975 5575);
DISPLAY 0.872340 (-1975 5575);
PAINT GREEN (-1975 5575);
DISPLAY INVISIBLE (-1975 5575);
FORCEPROP 2 LAST CDS_LIB standard
J 0
(-1650 5700);
PAINT MONO (-1650 5700);
DISPLAY INVISIBLE (-1650 5700);
FORCEADD OFFPAGE..2
(-1625 5550);
FORCEPROP 2 LAST $XR0 80 
J 0
(-1436 5550);
DISPLAY 0.638298 (-1436 5550);
PAINT MONO (-1436 5550);
FORCEPROP 2 LAST PATH I126
J 0
(-1425 5600);
DISPLAY 0.680851 (-1425 5600);
DISPLAY INVISIBLE (-1425 5600);
FORCEPROP 1 LAST COMMENT_BODY TRUE
J 0
(-1670 5455);
DISPLAY 0.872340 (-1670 5455);
PAINT GREEN (-1670 5455);
DISPLAY INVISIBLE (-1670 5455);
FORCEPROP 1 LAST OFFPAGE TRUE
J 0
(-1300 5425);
DISPLAY 0.872340 (-1300 5425);
PAINT GREEN (-1300 5425);
DISPLAY INVISIBLE (-1300 5425);
FORCEPROP 2 LAST CDS_LIB standard
J 0
(-1625 5550);
DISPLAY INVISIBLE (-1625 5550);
FORCEADD OFFPAGE..1
R 2
(-1650 5750);
FORCEPROP 2 LAST $XR0 80 
J 0
(-1464 5750);
DISPLAY 0.638298 (-1464 5750);
PAINT MONO (-1464 5750);
FORCEPROP 2 LAST PATH I127
J 0
(-1450 5800);
DISPLAY 0.680851 (-1450 5800);
DISPLAY INVISIBLE (-1450 5800);
FORCEPROP 1 LAST COMMENT_BODY TRUE
J 2
(-1775 5650);
DISPLAY 0.872340 (-1775 5650);
PAINT GREEN (-1775 5650);
DISPLAY INVISIBLE (-1775 5650);
FORCEPROP 1 LAST OFFPAGE TRUE
J 2
(-1975 5625);
DISPLAY 0.872340 (-1975 5625);
PAINT GREEN (-1975 5625);
DISPLAY INVISIBLE (-1975 5625);
FORCEPROP 2 LAST CDS_LIB standard
J 0
(-1650 5750);
PAINT MONO (-1650 5750);
DISPLAY INVISIBLE (-1650 5750);
FORCEADD OFFPAGE..2
(-1650 5850);
FORCEPROP 2 LAST $XR0 149 
J 0
(-1461 5850);
DISPLAY 0.638298 (-1461 5850);
PAINT MONO (-1461 5850);
FORCEPROP 2 LAST PATH I128
J 0
(-1450 5900);
DISPLAY 0.680851 (-1450 5900);
DISPLAY INVISIBLE (-1450 5900);
FORCEPROP 1 LAST COMMENT_BODY TRUE
J 0
(-1695 5755);
DISPLAY 0.872340 (-1695 5755);
PAINT GREEN (-1695 5755);
DISPLAY INVISIBLE (-1695 5755);
FORCEPROP 1 LAST OFFPAGE TRUE
J 0
(-1325 5725);
DISPLAY 0.872340 (-1325 5725);
PAINT GREEN (-1325 5725);
DISPLAY INVISIBLE (-1325 5725);
FORCEPROP 2 LAST CDS_LIB standard
J 0
(-1650 5850);
DISPLAY INVISIBLE (-1650 5850);
FORCEADD OFFPAGE..1
R 2
(-1650 5800);
FORCEPROP 2 LAST $XR0 149 
J 0
(-1464 5800);
DISPLAY 0.638298 (-1464 5800);
PAINT MONO (-1464 5800);
FORCEPROP 2 LAST PATH I129
J 0
(-1450 5850);
DISPLAY 0.680851 (-1450 5850);
DISPLAY INVISIBLE (-1450 5850);
FORCEPROP 1 LAST COMMENT_BODY TRUE
J 2
(-1775 5700);
DISPLAY 0.872340 (-1775 5700);
PAINT GREEN (-1775 5700);
DISPLAY INVISIBLE (-1775 5700);
FORCEPROP 1 LAST OFFPAGE TRUE
J 2
(-1975 5675);
DISPLAY 0.872340 (-1975 5675);
PAINT GREEN (-1975 5675);
DISPLAY INVISIBLE (-1975 5675);
FORCEPROP 2 LAST CDS_LIB standard
J 2
(-1650 5800);
DISPLAY INVISIBLE (-1650 5800);
FORCEADD OFFPAGE..2
(-1650 5950);
FORCEPROP 2 LAST $XR0 149 
J 0
(-1461 5950);
DISPLAY 0.638298 (-1461 5950);
PAINT MONO (-1461 5950);
FORCEPROP 2 LAST PATH I130
J 0
(-1450 6000);
DISPLAY 0.680851 (-1450 6000);
DISPLAY INVISIBLE (-1450 6000);
FORCEPROP 1 LAST COMMENT_BODY TRUE
J 0
(-1695 5855);
DISPLAY 0.872340 (-1695 5855);
PAINT GREEN (-1695 5855);
DISPLAY INVISIBLE (-1695 5855);
FORCEPROP 1 LAST OFFPAGE TRUE
J 0
(-1325 5825);
DISPLAY 0.872340 (-1325 5825);
PAINT GREEN (-1325 5825);
DISPLAY INVISIBLE (-1325 5825);
FORCEPROP 2 LAST CDS_LIB standard
J 0
(-1650 5950);
DISPLAY INVISIBLE (-1650 5950);
FORCEADD OFFPAGE..2
(-1650 5900);
FORCEPROP 2 LAST $XR0 149 
J 0
(-1461 5900);
DISPLAY 0.638298 (-1461 5900);
PAINT MONO (-1461 5900);
FORCEPROP 2 LAST PATH I131
J 0
(-1450 5950);
DISPLAY 0.680851 (-1450 5950);
DISPLAY INVISIBLE (-1450 5950);
FORCEPROP 1 LAST COMMENT_BODY TRUE
J 0
(-1695 5805);
DISPLAY 0.872340 (-1695 5805);
PAINT GREEN (-1695 5805);
DISPLAY INVISIBLE (-1695 5805);
FORCEPROP 1 LAST OFFPAGE TRUE
J 0
(-1325 5775);
DISPLAY 0.872340 (-1325 5775);
PAINT GREEN (-1325 5775);
DISPLAY INVISIBLE (-1325 5775);
FORCEPROP 2 LAST CDS_LIB standard
J 0
(-1650 5900);
DISPLAY INVISIBLE (-1650 5900);
FORCEADD Q_RES..1
(-3975 5950);
FORCEPROP 1 LAST LOCATION R1352
J 0
(-4175 5950);
DISPLAY 0.489362 (-4175 5950);
PAINT SKYBLUE (-4175 5950);
FORCEPROP 0 LAST $SEC 1
J 0
(-4100 6000);
DISPLAY 0.680851 (-4100 6000);
PAINT MONO (-4100 6000);
DISPLAY INVISIBLE (-4100 6000);
FORCEPROP 0 LAST CDS_SEC 1
J 0
(-4100 6000);
DISPLAY 0.680851 (-4100 6000);
DISPLAY INVISIBLE (-4100 6000);
FORCEPROP 1 LASTPIN (-4075 5950) $PN 1
J 0
(-4063 5962);
DISPLAY 0.489362 (-4063 5962);
PAINT MONO (-4063 5962);
FORCEPROP 1 LASTPIN (-3875 5950) $PN 2
J 0
(-3913 5962);
DISPLAY 0.489362 (-3913 5962);
PAINT MONO (-3913 5962);
FORCEPROP 1 LAST VALUE 0
J 2
(-3825 5950);
DISPLAY 0.489362 (-3825 5950);
PAINT SKYBLUE (-3825 5950);
FORCEPROP 2 LAST CDS_LIB pure_quanta
J 0
(-3975 5950);
DISPLAY INVISIBLE (-3975 5950);
FORCEPROP 1 LAST PATH I132
J 0
(-4025 6100);
DISPLAY 0.978723 (-4025 6100);
PAINT WHITE (-4025 6100);
DISPLAY INVISIBLE (-4025 6100);
FORCEPROP 1 LAST WATTAGE 1/16W
J 2
(-4000 5800);
DISPLAY 0.978723 (-4000 5800);
PAINT SKYBLUE (-4000 5800);
DISPLAY INVISIBLE (-4000 5800);
FORCEPROP 1 LAST MATERIAL CHIP
J 0
(-3750 5950);
DISPLAY 0.617021 (-3750 5950);
PAINT SKYBLUE (-3750 5950);
DISPLAY INVISIBLE (-3750 5950);
FORCEPROP 1 LAST TOLERANCE 5%
J 0
(-3975 5850);
DISPLAY 0.978723 (-3975 5850);
PAINT SKYBLUE (-3975 5850);
DISPLAY INVISIBLE (-3975 5850);
FORCEPROP 1 LAST PART_NUMBER CS00002JB38
J 0
(-4025 6050);
DISPLAY 0.978723 (-4025 6050);
PAINT SKYBLUE (-4025 6050);
DISPLAY INVISIBLE (-4025 6050);
FORCEPROP 1 LAST PACK_TYPE 0402LF
J 0
(-3725 5800);
DISPLAY 0.978723 (-3725 5800);
PAINT SKYBLUE (-3725 5800);
DISPLAY INVISIBLE (-3725 5800);
FORCEADD Q_RES..1
(-3975 5900);
FORCEPROP 1 LAST LOCATION R1353
J 0
(-4175 5900);
DISPLAY 0.489362 (-4175 5900);
PAINT SKYBLUE (-4175 5900);
FORCEPROP 0 LAST $SEC 1
J 0
(-4100 5950);
DISPLAY 0.680851 (-4100 5950);
PAINT MONO (-4100 5950);
DISPLAY INVISIBLE (-4100 5950);
FORCEPROP 0 LAST CDS_SEC 1
J 0
(-4100 5950);
DISPLAY 0.680851 (-4100 5950);
DISPLAY INVISIBLE (-4100 5950);
FORCEPROP 1 LASTPIN (-4075 5900) $PN 1
J 0
(-4063 5912);
DISPLAY 0.489362 (-4063 5912);
PAINT MONO (-4063 5912);
FORCEPROP 1 LASTPIN (-3875 5900) $PN 2
J 0
(-3913 5912);
DISPLAY 0.489362 (-3913 5912);
PAINT MONO (-3913 5912);
FORCEPROP 1 LAST VALUE 0
J 2
(-3825 5900);
DISPLAY 0.489362 (-3825 5900);
PAINT SKYBLUE (-3825 5900);
FORCEPROP 2 LAST CDS_LIB pure_quanta
J 0
(-3975 5900);
DISPLAY INVISIBLE (-3975 5900);
FORCEPROP 1 LAST PATH I133
J 0
(-4025 6050);
DISPLAY 0.978723 (-4025 6050);
PAINT WHITE (-4025 6050);
DISPLAY INVISIBLE (-4025 6050);
FORCEPROP 1 LAST WATTAGE 1/16W
J 2
(-4000 5750);
DISPLAY 0.978723 (-4000 5750);
PAINT SKYBLUE (-4000 5750);
DISPLAY INVISIBLE (-4000 5750);
FORCEPROP 1 LAST MATERIAL CHIP
J 0
(-3750 5900);
DISPLAY 0.617021 (-3750 5900);
PAINT SKYBLUE (-3750 5900);
DISPLAY INVISIBLE (-3750 5900);
FORCEPROP 1 LAST TOLERANCE 5%
J 0
(-3975 5800);
DISPLAY 0.978723 (-3975 5800);
PAINT SKYBLUE (-3975 5800);
DISPLAY INVISIBLE (-3975 5800);
FORCEPROP 1 LAST PART_NUMBER CS00002JB38
J 0
(-4025 6000);
DISPLAY 0.978723 (-4025 6000);
PAINT SKYBLUE (-4025 6000);
DISPLAY INVISIBLE (-4025 6000);
FORCEPROP 1 LAST PACK_TYPE 0402LF
J 0
(-3725 5750);
DISPLAY 0.978723 (-3725 5750);
PAINT SKYBLUE (-3725 5750);
DISPLAY INVISIBLE (-3725 5750);
FORCEADD Q_CAP..1
(-2350 5325);
FORCEPROP 1 LAST LOCATION C87
J 0
(-2300 5425);
DISPLAY 0.489362 (-2300 5425);
PAINT SKYBLUE (-2300 5425);
FORCEPROP 0 LAST $SEC 1
J 0
(-2300 5450);
DISPLAY 0.680851 (-2300 5450);
PAINT MONO (-2300 5450);
DISPLAY INVISIBLE (-2300 5450);
FORCEPROP 0 LAST CDS_SEC 1
J 0
(-2300 5450);
DISPLAY 0.680851 (-2300 5450);
DISPLAY INVISIBLE (-2300 5450);
FORCEPROP 1 LASTPIN (-2350 5425) $PN 1
J 0
(-2340 5405);
DISPLAY 0.489362 (-2340 5405);
PAINT MONO (-2340 5405);
FORCEPROP 1 LASTPIN (-2350 5225) $PN 2
J 0
(-2340 5205);
DISPLAY 0.489362 (-2340 5205);
PAINT MONO (-2340 5205);
FORCEPROP 1 LAST MATERIAL X7R
J 0
(-2300 5225);
DISPLAY 0.489362 (-2300 5225);
PAINT SKYBLUE (-2300 5225);
FORCEPROP 1 LAST TOLERANCE 10%
J 0
(-2300 5275);
DISPLAY 0.489362 (-2300 5275);
PAINT SKYBLUE (-2300 5275);
FORCEPROP 1 LAST VALUE 0.001UF
J 0
(-2300 5375);
DISPLAY 0.489362 (-2300 5375);
PAINT SKYBLUE (-2300 5375);
FORCEPROP 1 LAST VOLTAGE 50V
J 0
(-2300 5325);
DISPLAY 0.489362 (-2300 5325);
PAINT SKYBLUE (-2300 5325);
FORCEPROP 1 LAST PACK_TYPE C0402
J 0
(-2300 5175);
DISPLAY 0.489362 (-2300 5175);
PAINT SKYBLUE (-2300 5175);
FORCEPROP 2 LAST CDS_LIB pure_quanta
J 0
(-2350 5325);
DISPLAY INVISIBLE (-2350 5325);
FORCEPROP 1 LAST PATH I134
J 0
(-2300 5475);
DISPLAY 0.978723 (-2300 5475);
PAINT WHITE (-2300 5475);
DISPLAY INVISIBLE (-2300 5475);
FORCEPROP 1 LAST PART_NUMBER CH30106KB19
J 0
(-2300 5225);
DISPLAY 0.808511 (-2300 5225);
PAINT SKYBLUE (-2300 5225);
DISPLAY INVISIBLE (-2300 5225);
FORCEADD Q_CAP..1
(-2575 5325);
FORCEPROP 1 LAST LOCATION C605
J 0
(-2525 5425);
DISPLAY 0.489362 (-2525 5425);
PAINT SKYBLUE (-2525 5425);
FORCEPROP 0 LAST $SEC 1
J 0
(-2525 5450);
DISPLAY 0.680851 (-2525 5450);
PAINT MONO (-2525 5450);
DISPLAY INVISIBLE (-2525 5450);
FORCEPROP 0 LAST CDS_SEC 1
J 0
(-2525 5450);
DISPLAY 0.680851 (-2525 5450);
DISPLAY INVISIBLE (-2525 5450);
FORCEPROP 1 LASTPIN (-2575 5425) $PN 1
J 0
(-2565 5405);
DISPLAY 0.489362 (-2565 5405);
PAINT MONO (-2565 5405);
FORCEPROP 1 LASTPIN (-2575 5225) $PN 2
J 0
(-2565 5205);
DISPLAY 0.489362 (-2565 5205);
PAINT MONO (-2565 5205);
FORCEPROP 1 LAST MATERIAL X7R
J 0
(-2525 5225);
DISPLAY 0.489362 (-2525 5225);
PAINT SKYBLUE (-2525 5225);
FORCEPROP 1 LAST TOLERANCE 10%
J 0
(-2525 5275);
DISPLAY 0.489362 (-2525 5275);
PAINT SKYBLUE (-2525 5275);
FORCEPROP 1 LAST VALUE 0.001UF
J 0
(-2525 5375);
DISPLAY 0.489362 (-2525 5375);
PAINT SKYBLUE (-2525 5375);
FORCEPROP 1 LAST VOLTAGE 50V
J 0
(-2525 5325);
DISPLAY 0.489362 (-2525 5325);
PAINT SKYBLUE (-2525 5325);
FORCEPROP 1 LAST PACK_TYPE C0402
J 0
(-2525 5175);
DISPLAY 0.489362 (-2525 5175);
PAINT SKYBLUE (-2525 5175);
FORCEPROP 2 LAST CDS_LIB pure_quanta
J 0
(-2575 5325);
DISPLAY INVISIBLE (-2575 5325);
FORCEPROP 1 LAST PATH I137
J 0
(-2525 5475);
DISPLAY 0.978723 (-2525 5475);
PAINT WHITE (-2525 5475);
DISPLAY INVISIBLE (-2525 5475);
FORCEPROP 1 LAST PART_NUMBER CH30106KB19
J 0
(-2525 5225);
DISPLAY 0.808511 (-2525 5225);
PAINT SKYBLUE (-2525 5225);
DISPLAY INVISIBLE (-2525 5225);
FORCEADD GND..1
(-2575 5100);
FORCEPROP 3 LASTPIN (-2575 5150) SIG_NAME GND\g
J 0
(-2565 5160);
DISPLAY 0.659574 (-2565 5160);
PAINT MONO (-2565 5160);
DISPLAY INVISIBLE (-2565 5160);
FORCEPROP 1 LAST SIZE 1B
J 0
(-2500 5050);
DISPLAY 0.872340 (-2500 5050);
PAINT GREEN (-2500 5050);
DISPLAY INVISIBLE (-2500 5050);
FORCEPROP 2 LAST CDS_LIB pure_quanta_power
J 0
(-2575 5100);
DISPLAY INVISIBLE (-2575 5100);
FORCEPROP 1 LAST PATH I138
J 0
(-2500 5100);
DISPLAY 0.872340 (-2500 5100);
PAINT AQUA (-2500 5100);
DISPLAY INVISIBLE (-2500 5100);
FORCEPROP 1 LAST HDL_POWER GND
J 0
(-2575 5250);
DISPLAY 0.872340 (-2575 5250);
PAINT GREEN (-2575 5250);
DISPLAY INVISIBLE (-2575 5250);
FORCEADD Q_CAP..1
(-2800 5325);
FORCEPROP 1 LAST LOCATION C604
J 0
(-2750 5425);
DISPLAY 0.489362 (-2750 5425);
PAINT SKYBLUE (-2750 5425);
FORCEPROP 0 LAST $SEC 1
J 0
(-2750 5475);
DISPLAY 0.680851 (-2750 5475);
PAINT MONO (-2750 5475);
DISPLAY INVISIBLE (-2750 5475);
FORCEPROP 0 LAST CDS_SEC 1
J 0
(-2750 5475);
DISPLAY 0.680851 (-2750 5475);
DISPLAY INVISIBLE (-2750 5475);
FORCEPROP 1 LASTPIN (-2800 5425) $PN 1
J 0
(-2790 5405);
DISPLAY 0.489362 (-2790 5405);
PAINT MONO (-2790 5405);
FORCEPROP 1 LASTPIN (-2800 5225) $PN 2
J 0
(-2790 5205);
DISPLAY 0.489362 (-2790 5205);
PAINT MONO (-2790 5205);
FORCEPROP 1 LAST MATERIAL X7R
J 0
(-2750 5225);
DISPLAY 0.489362 (-2750 5225);
PAINT SKYBLUE (-2750 5225);
FORCEPROP 1 LAST TOLERANCE 10%
J 0
(-2750 5275);
DISPLAY 0.489362 (-2750 5275);
PAINT SKYBLUE (-2750 5275);
FORCEPROP 1 LAST VALUE 0.001UF
J 0
(-2750 5375);
DISPLAY 0.489362 (-2750 5375);
PAINT SKYBLUE (-2750 5375);
FORCEPROP 1 LAST VOLTAGE 50V
J 0
(-2750 5325);
DISPLAY 0.489362 (-2750 5325);
PAINT SKYBLUE (-2750 5325);
FORCEPROP 1 LAST PACK_TYPE C0402
J 0
(-2750 5175);
DISPLAY 0.489362 (-2750 5175);
PAINT SKYBLUE (-2750 5175);
FORCEPROP 2 LAST CDS_LIB pure_quanta
J 0
(-2800 5325);
DISPLAY INVISIBLE (-2800 5325);
FORCEPROP 1 LAST PATH I140
J 0
(-2750 5475);
DISPLAY 0.978723 (-2750 5475);
PAINT WHITE (-2750 5475);
DISPLAY INVISIBLE (-2750 5475);
FORCEPROP 1 LAST PART_NUMBER CH30106KB19
J 0
(-2750 5225);
DISPLAY 0.808511 (-2750 5225);
PAINT SKYBLUE (-2750 5225);
DISPLAY INVISIBLE (-2750 5225);
FORCEADD GND..1
(-2800 5100);
FORCEPROP 3 LASTPIN (-2800 5150) SIG_NAME GND\g
J 0
(-2790 5160);
DISPLAY 0.659574 (-2790 5160);
PAINT MONO (-2790 5160);
DISPLAY INVISIBLE (-2790 5160);
FORCEPROP 1 LAST SIZE 1B
J 0
(-2725 5050);
DISPLAY 0.872340 (-2725 5050);
PAINT GREEN (-2725 5050);
DISPLAY INVISIBLE (-2725 5050);
FORCEPROP 2 LAST CDS_LIB pure_quanta_power
J 0
(-2800 5100);
DISPLAY INVISIBLE (-2800 5100);
FORCEPROP 1 LAST PATH I141
J 0
(-2725 5100);
DISPLAY 0.872340 (-2725 5100);
PAINT AQUA (-2725 5100);
DISPLAY INVISIBLE (-2725 5100);
FORCEPROP 1 LAST HDL_POWER GND
J 0
(-2800 5250);
DISPLAY 0.872340 (-2800 5250);
PAINT GREEN (-2800 5250);
DISPLAY INVISIBLE (-2800 5250);
FORCEADD SCONN20_HSU2101L00007H..1
(-5125 5725);
FORCEPROP 1 LAST LOCATION J54
J 0
(-5219 6281);
DISPLAY 0.489362 (-5219 6281);
PAINT SKYBLUE (-5219 6281);
FORCEPROP 0 LAST $SEC 1
J 0
(-5200 6425);
DISPLAY 0.680851 (-5200 6425);
PAINT MONO (-5200 6425);
DISPLAY INVISIBLE (-5200 6425);
FORCEPROP 0 LAST CDS_SEC 1
J 0
(-5200 6425);
DISPLAY 0.680851 (-5200 6425);
DISPLAY INVISIBLE (-5200 6425);
FORCEPROP 0 LASTPIN (-5375 5950) $PN 1
J 2
(-5385 5960);
DISPLAY 0.489362 (-5385 5960);
PAINT MONO (-5385 5960);
FORCEPROP 0 LASTPIN (-4875 5950) $PN 2
J 0
(-4865 5960);
DISPLAY 0.489362 (-4865 5960);
PAINT MONO (-4865 5960);
FORCEPROP 0 LASTPIN (-5375 5900) $PN 3
J 2
(-5385 5910);
DISPLAY 0.489362 (-5385 5910);
PAINT MONO (-5385 5910);
FORCEPROP 0 LASTPIN (-4875 5900) $PN 4
J 0
(-4865 5910);
DISPLAY 0.489362 (-4865 5910);
PAINT MONO (-4865 5910);
FORCEPROP 0 LASTPIN (-5375 5850) $PN 5
J 2
(-5385 5860);
DISPLAY 0.489362 (-5385 5860);
PAINT MONO (-5385 5860);
FORCEPROP 0 LASTPIN (-4875 5850) $PN 6
J 0
(-4865 5860);
DISPLAY 0.489362 (-4865 5860);
PAINT MONO (-4865 5860);
FORCEPROP 0 LASTPIN (-5375 5800) $PN 7
J 2
(-5385 5810);
DISPLAY 0.489362 (-5385 5810);
PAINT MONO (-5385 5810);
FORCEPROP 0 LASTPIN (-4875 5800) $PN 8
J 0
(-4865 5810);
DISPLAY 0.489362 (-4865 5810);
PAINT MONO (-4865 5810);
FORCEPROP 0 LASTPIN (-5375 5750) $PN 9
J 2
(-5385 5760);
DISPLAY 0.489362 (-5385 5760);
PAINT MONO (-5385 5760);
FORCEPROP 0 LASTPIN (-4875 5750) $PN 10
J 0
(-4865 5760);
DISPLAY 0.489362 (-4865 5760);
PAINT MONO (-4865 5760);
FORCEPROP 0 LASTPIN (-5375 5700) $PN 11
J 2
(-5385 5710);
DISPLAY 0.489362 (-5385 5710);
PAINT MONO (-5385 5710);
FORCEPROP 0 LASTPIN (-4875 5700) $PN 12
J 0
(-4865 5710);
DISPLAY 0.489362 (-4865 5710);
PAINT MONO (-4865 5710);
FORCEPROP 0 LASTPIN (-5375 5650) $PN 13
J 2
(-5385 5660);
DISPLAY 0.489362 (-5385 5660);
PAINT MONO (-5385 5660);
FORCEPROP 0 LASTPIN (-4875 5650) $PN 14
J 0
(-4865 5660);
DISPLAY 0.489362 (-4865 5660);
PAINT MONO (-4865 5660);
FORCEPROP 0 LASTPIN (-5375 5600) $PN 15
J 2
(-5385 5610);
DISPLAY 0.489362 (-5385 5610);
PAINT MONO (-5385 5610);
FORCEPROP 0 LASTPIN (-4875 5600) $PN 16
J 0
(-4865 5610);
DISPLAY 0.489362 (-4865 5610);
PAINT MONO (-4865 5610);
FORCEPROP 0 LASTPIN (-5375 5550) $PN 17
J 2
(-5385 5560);
DISPLAY 0.489362 (-5385 5560);
PAINT MONO (-5385 5560);
FORCEPROP 0 LASTPIN (-4875 5550) $PN 18
J 0
(-4865 5560);
DISPLAY 0.489362 (-4865 5560);
PAINT MONO (-4865 5560);
FORCEPROP 0 LASTPIN (-5375 5500) $PN 19
J 2
(-5385 5510);
DISPLAY 0.489362 (-5385 5510);
PAINT MONO (-5385 5510);
FORCEPROP 0 LASTPIN (-4875 5500) $PN 20
J 0
(-4865 5510);
DISPLAY 0.489362 (-4865 5510);
PAINT MONO (-4865 5510);
FORCEPROP 2 LAST PART_TYPE SMLF
J 0
(-5200 6375);
DISPLAY 0.680851 (-5200 6375);
FORCEPROP 1 LAST MATERIAL IO
J 0
(-5219 6007);
DISPLAY 0.489362 (-5219 6007);
PAINT SKYBLUE (-5219 6007);
FORCEPROP 2 LAST VALUE SCONN20_HSU2101-L0000-7H
J 0
(-5200 6325);
DISPLAY 0.489362 (-5200 6325);
PAINT SKYBLUE (-5200 6325);
FORCEPROP 1 LAST PART_NUMBER DFHD20MS153
J 0
(-5219 6134);
DISPLAY 0.489362 (-5219 6134);
PAINT SKYBLUE (-5219 6134);
FORCEPROP 2 LAST CDS_LIB pure_quanta
J 0
(-5125 5725);
DISPLAY INVISIBLE (-5125 5725);
FORCEPROP 1 LAST NEEDS_NO_SIZE TRUE
J 0
(-5125 5725);
DISPLAY 0.723404 (-5125 5725);
PAINT GREEN (-5125 5725);
DISPLAY INVISIBLE (-5125 5725);
FORCEPROP 1 LAST CDS_LMAN_SYM_OUTLINE -100,275,100,-275
J 0
(-5125 5725);
DISPLAY 0.468085 (-5125 5725);
PAINT GREEN (-5125 5725);
DISPLAY INVISIBLE (-5125 5725);
FORCEPROP 1 LAST PATH I142
J 0
(-5125 5725);
DISPLAY 0.723404 (-5125 5725);
PAINT GREEN (-5125 5725);
DISPLAY INVISIBLE (-5125 5725);
FORCEADD GND..1
(-5475 5350);
FORCEPROP 3 LASTPIN (-5475 5400) SIG_NAME GND\g
J 0
(-5465 5410);
DISPLAY 0.659574 (-5465 5410);
PAINT MONO (-5465 5410);
DISPLAY INVISIBLE (-5465 5410);
FORCEPROP 2 LAST CDS_LIB pure_quanta_power
J 0
(-5475 5350);
DISPLAY INVISIBLE (-5475 5350);
FORCEPROP 1 LAST SIZE 1B
J 0
(-5400 5300);
DISPLAY 0.872340 (-5400 5300);
PAINT GREEN (-5400 5300);
DISPLAY INVISIBLE (-5400 5300);
FORCEPROP 1 LAST PATH I143
J 0
(-5400 5350);
DISPLAY 0.872340 (-5400 5350);
PAINT AQUA (-5400 5350);
DISPLAY INVISIBLE (-5400 5350);
FORCEPROP 1 LAST HDL_POWER GND
J 0
(-5475 5500);
DISPLAY 0.872340 (-5475 5500);
PAINT GREEN (-5475 5500);
DISPLAY INVISIBLE (-5475 5500);
FORCEADD UNIVERSAL_POWER..1
(-5600 6200);
FORCEPROP 3 LASTPIN (-5600 6150) SIG_NAME PVDD18_S5_P0\g
J 0
(-5590 6160);
DISPLAY 0.659574 (-5590 6160);
PAINT MONO (-5590 6160);
DISPLAY INVISIBLE (-5590 6160);
FORCEPROP 1 LAST HDL_POWER PVDD18_S5_P0
J 1
(-5575 6250);
DISPLAY 0.489362 (-5575 6250);
PAINT GREEN (-5575 6250);
FORCEPROP 2 LAST CDS_LIB pure_quanta_power
J 0
(-5600 6200);
DISPLAY INVISIBLE (-5600 6200);
FORCEPROP 1 LAST PATH I144
J 0
(-5550 6225);
DISPLAY 0.872340 (-5550 6225);
PAINT AQUA (-5550 6225);
DISPLAY INVISIBLE (-5550 6225);
FORCEADD UNIVERSAL_POWER..1
(-6050 6450);
FORCEPROP 3 LASTPIN (-6050 6400) SIG_NAME PVDD18_S5_P0\g
J 0
(-6040 6410);
DISPLAY 0.659574 (-6040 6410);
PAINT MONO (-6040 6410);
DISPLAY INVISIBLE (-6040 6410);
FORCEPROP 1 LAST HDL_POWER PVDD18_S5_P0
J 1
(-6025 6500);
DISPLAY 0.489362 (-6025 6500);
PAINT GREEN (-6025 6500);
FORCEPROP 2 LAST CDS_LIB pure_quanta_power
J 0
(-6050 6450);
DISPLAY INVISIBLE (-6050 6450);
FORCEPROP 1 LAST PATH I145
J 0
(-6000 6475);
DISPLAY 0.872340 (-6000 6475);
PAINT AQUA (-6000 6475);
DISPLAY INVISIBLE (-6000 6475);
FORCEADD Q_RES..2
(-6050 6250);
FORCEPROP 1 LAST LOCATION R1621
J 0
(-6000 6400);
DISPLAY 0.489362 (-6000 6400);
PAINT SKYBLUE (-6000 6400);
FORCEPROP 2 LAST $SEC 1
J 0
(-6000 6475);
DISPLAY 0.680851 (-6000 6475);
PAINT MONO (-6000 6475);
DISPLAY INVISIBLE (-6000 6475);
FORCEPROP 2 LAST CDS_SEC 1
J 0
(-6000 6475);
DISPLAY 1.021277 (-6000 6475);
DISPLAY INVISIBLE (-6000 6475);
FORCEPROP 1 LASTPIN (-6050 6350) $PN 1
J 0
(-6045 6312);
DISPLAY 0.489362 (-6045 6312);
FORCEPROP 1 LASTPIN (-6050 6150) $PN 2
J 0
(-6045 6160);
DISPLAY 0.489362 (-6045 6160);
FORCEPROP 1 LAST WATTAGE 1/16W
J 0
(-6000 6250);
DISPLAY 0.489362 (-6000 6250);
PAINT SKYBLUE (-6000 6250);
FORCEPROP 1 LAST MATERIAL CHIP
J 0
(-6000 6200);
DISPLAY 0.489362 (-6000 6200);
PAINT SKYBLUE (-6000 6200);
FORCEPROP 1 LAST TOLERANCE 5%
J 0
(-6000 6300);
DISPLAY 0.489362 (-6000 6300);
PAINT SKYBLUE (-6000 6300);
FORCEPROP 1 LAST VALUE 1K
J 0
(-6000 6350);
DISPLAY 0.489362 (-6000 6350);
PAINT SKYBLUE (-6000 6350);
FORCEPROP 1 LAST PACK_TYPE 0402LF
J 0
(-6000 6150);
DISPLAY 0.489362 (-6000 6150);
PAINT SKYBLUE (-6000 6150);
FORCEPROP 2 LAST CDS_LIB pure_quanta
J 0
(-6050 6250);
DISPLAY INVISIBLE (-6050 6250);
FORCEPROP 1 LAST PATH I146
J 0
(-6000 6425);
DISPLAY 0.978723 (-6000 6425);
PAINT WHITE (-6000 6425);
DISPLAY INVISIBLE (-6000 6425);
FORCEPROP 1 LAST PART_NUMBER TMP_QCS21002JB34
J 0
(-6000 6100);
DISPLAY 0.489362 (-6000 6100);
PAINT SKYBLUE (-6000 6100);
DISPLAY INVISIBLE (-6000 6100);
FORCEADD Q_RES..1
(-6300 5650);
FORCEPROP 1 LAST LOCATION R477
J 0
(-6525 5650);
DISPLAY 0.489362 (-6525 5650);
PAINT SKYBLUE (-6525 5650);
FORCEPROP 2 LAST $SEC 1
J 0
(-6350 5850);
DISPLAY 0.680851 (-6350 5850);
PAINT MONO (-6350 5850);
DISPLAY INVISIBLE (-6350 5850);
FORCEPROP 2 LAST CDS_SEC 1
J 0
(-6350 5850);
DISPLAY 1.021277 (-6350 5850);
DISPLAY INVISIBLE (-6350 5850);
FORCEPROP 1 LASTPIN (-6400 5650) $PN 1
J 0
(-6388 5662);
DISPLAY 0.489362 (-6388 5662);
PAINT MONO (-6388 5662);
FORCEPROP 1 LASTPIN (-6200 5650) $PN 2
J 0
(-6238 5662);
DISPLAY 0.489362 (-6238 5662);
PAINT MONO (-6238 5662);
FORCEPROP 1 LAST VALUE 33
J 2
(-6125 5650);
DISPLAY 0.489362 (-6125 5650);
PAINT SKYBLUE (-6125 5650);
FORCEPROP 2 LAST CDS_LIB pure_quanta
J 0
(-6300 5650);
DISPLAY INVISIBLE (-6300 5650);
FORCEPROP 1 LAST PATH I147
J 0
(-6350 5800);
DISPLAY 0.978723 (-6350 5800);
PAINT WHITE (-6350 5800);
DISPLAY INVISIBLE (-6350 5800);
FORCEPROP 1 LAST WATTAGE 1/16W
J 2
(-6325 5500);
DISPLAY 0.978723 (-6325 5500);
PAINT SKYBLUE (-6325 5500);
DISPLAY INVISIBLE (-6325 5500);
FORCEPROP 1 LAST MATERIAL CHIP
J 0
(-6350 5600);
DISPLAY 0.489362 (-6350 5600);
PAINT SKYBLUE (-6350 5600);
DISPLAY INVISIBLE (-6350 5600);
FORCEPROP 1 LAST TOLERANCE 5%
J 0
(-6300 5550);
DISPLAY 0.978723 (-6300 5550);
PAINT SKYBLUE (-6300 5550);
DISPLAY INVISIBLE (-6300 5550);
FORCEPROP 1 LAST PART_NUMBER CS03302JB29
J 0
(-6350 5750);
DISPLAY 0.978723 (-6350 5750);
PAINT SKYBLUE (-6350 5750);
DISPLAY INVISIBLE (-6350 5750);
FORCEPROP 1 LAST PACK_TYPE 0402LF
J 0
(-6225 5600);
DISPLAY 0.489362 (-6225 5600);
PAINT SKYBLUE (-6225 5600);
DISPLAY INVISIBLE (-6225 5600);
FORCEADD Q_RES..1
(-6300 5700);
FORCEPROP 1 LAST LOCATION R476
J 0
(-6525 5700);
DISPLAY 0.489362 (-6525 5700);
PAINT SKYBLUE (-6525 5700);
FORCEPROP 2 LAST $SEC 1
J 0
(-6350 5900);
DISPLAY 0.680851 (-6350 5900);
PAINT MONO (-6350 5900);
DISPLAY INVISIBLE (-6350 5900);
FORCEPROP 2 LAST CDS_SEC 1
J 0
(-6350 5900);
DISPLAY 1.021277 (-6350 5900);
DISPLAY INVISIBLE (-6350 5900);
FORCEPROP 1 LASTPIN (-6400 5700) $PN 1
J 0
(-6388 5712);
DISPLAY 0.489362 (-6388 5712);
PAINT MONO (-6388 5712);
FORCEPROP 1 LASTPIN (-6200 5700) $PN 2
J 0
(-6238 5712);
DISPLAY 0.489362 (-6238 5712);
PAINT MONO (-6238 5712);
FORCEPROP 1 LAST VALUE 33
J 2
(-6125 5700);
DISPLAY 0.489362 (-6125 5700);
PAINT SKYBLUE (-6125 5700);
FORCEPROP 2 LAST CDS_LIB pure_quanta
J 0
(-6300 5700);
DISPLAY INVISIBLE (-6300 5700);
FORCEPROP 1 LAST PATH I148
J 0
(-6350 5850);
DISPLAY 0.978723 (-6350 5850);
PAINT WHITE (-6350 5850);
DISPLAY INVISIBLE (-6350 5850);
FORCEPROP 1 LAST WATTAGE 1/16W
J 2
(-6325 5550);
DISPLAY 0.978723 (-6325 5550);
PAINT SKYBLUE (-6325 5550);
DISPLAY INVISIBLE (-6325 5550);
FORCEPROP 1 LAST MATERIAL CHIP
J 0
(-6350 5650);
DISPLAY 0.489362 (-6350 5650);
PAINT SKYBLUE (-6350 5650);
DISPLAY INVISIBLE (-6350 5650);
FORCEPROP 1 LAST TOLERANCE 5%
J 0
(-6300 5600);
DISPLAY 0.978723 (-6300 5600);
PAINT SKYBLUE (-6300 5600);
DISPLAY INVISIBLE (-6300 5600);
FORCEPROP 1 LAST PART_NUMBER CS03302JB29
J 0
(-6350 5800);
DISPLAY 0.978723 (-6350 5800);
PAINT SKYBLUE (-6350 5800);
DISPLAY INVISIBLE (-6350 5800);
FORCEPROP 1 LAST PACK_TYPE 0402LF
J 0
(-6225 5650);
DISPLAY 0.489362 (-6225 5650);
PAINT SKYBLUE (-6225 5650);
DISPLAY INVISIBLE (-6225 5650);
FORCEADD Q_RES..1
(-6300 5750);
FORCEPROP 1 LAST LOCATION R1620
J 0
(-6525 5750);
DISPLAY 0.489362 (-6525 5750);
PAINT SKYBLUE (-6525 5750);
FORCEPROP 2 LAST $SEC 1
J 0
(-6350 5950);
DISPLAY 0.680851 (-6350 5950);
PAINT MONO (-6350 5950);
DISPLAY INVISIBLE (-6350 5950);
FORCEPROP 2 LAST CDS_SEC 1
J 0
(-6350 5950);
DISPLAY 1.021277 (-6350 5950);
DISPLAY INVISIBLE (-6350 5950);
FORCEPROP 1 LASTPIN (-6400 5750) $PN 1
J 0
(-6388 5762);
DISPLAY 0.489362 (-6388 5762);
FORCEPROP 1 LASTPIN (-6200 5750) $PN 2
J 0
(-6238 5762);
DISPLAY 0.489362 (-6238 5762);
FORCEPROP 1 LAST VALUE 33
J 2
(-6125 5750);
DISPLAY 0.489362 (-6125 5750);
PAINT SKYBLUE (-6125 5750);
FORCEPROP 2 LAST CDS_LIB pure_quanta
J 0
(-6300 5750);
DISPLAY INVISIBLE (-6300 5750);
FORCEPROP 1 LAST PATH I149
J 0
(-6350 5900);
DISPLAY 0.978723 (-6350 5900);
PAINT WHITE (-6350 5900);
DISPLAY INVISIBLE (-6350 5900);
FORCEPROP 1 LAST WATTAGE 1/16W
J 2
(-6325 5600);
DISPLAY 0.978723 (-6325 5600);
PAINT SKYBLUE (-6325 5600);
DISPLAY INVISIBLE (-6325 5600);
FORCEPROP 1 LAST MATERIAL CHIP
J 0
(-6350 5700);
DISPLAY 0.489362 (-6350 5700);
PAINT SKYBLUE (-6350 5700);
DISPLAY INVISIBLE (-6350 5700);
FORCEPROP 1 LAST TOLERANCE 5%
J 0
(-6300 5650);
DISPLAY 0.978723 (-6300 5650);
PAINT SKYBLUE (-6300 5650);
DISPLAY INVISIBLE (-6300 5650);
FORCEPROP 1 LAST PART_NUMBER CS03302JB29
J 0
(-6350 5850);
DISPLAY 0.978723 (-6350 5850);
PAINT SKYBLUE (-6350 5850);
DISPLAY INVISIBLE (-6350 5850);
FORCEPROP 1 LAST PACK_TYPE 0402LF
J 0
(-6225 5700);
DISPLAY 0.489362 (-6225 5700);
PAINT SKYBLUE (-6225 5700);
DISPLAY INVISIBLE (-6225 5700);
FORCEADD Q_RES..1
(-6300 5600);
FORCEPROP 1 LAST LOCATION R478
J 0
(-6525 5600);
DISPLAY 0.489362 (-6525 5600);
PAINT SKYBLUE (-6525 5600);
FORCEPROP 2 LAST $SEC 1
J 0
(-6350 5800);
DISPLAY 0.680851 (-6350 5800);
PAINT MONO (-6350 5800);
DISPLAY INVISIBLE (-6350 5800);
FORCEPROP 2 LAST CDS_SEC 1
J 0
(-6350 5800);
DISPLAY 1.021277 (-6350 5800);
DISPLAY INVISIBLE (-6350 5800);
FORCEPROP 1 LASTPIN (-6400 5600) $PN 1
J 0
(-6388 5612);
DISPLAY 0.489362 (-6388 5612);
PAINT MONO (-6388 5612);
FORCEPROP 1 LASTPIN (-6200 5600) $PN 2
J 0
(-6238 5612);
DISPLAY 0.489362 (-6238 5612);
PAINT MONO (-6238 5612);
FORCEPROP 1 LAST VALUE 33
J 2
(-6125 5600);
DISPLAY 0.489362 (-6125 5600);
PAINT SKYBLUE (-6125 5600);
FORCEPROP 2 LAST CDS_LIB pure_quanta
J 0
(-6300 5600);
DISPLAY INVISIBLE (-6300 5600);
FORCEPROP 1 LAST PATH I150
J 0
(-6350 5750);
DISPLAY 0.978723 (-6350 5750);
PAINT WHITE (-6350 5750);
DISPLAY INVISIBLE (-6350 5750);
FORCEPROP 1 LAST WATTAGE 1/16W
J 2
(-6325 5450);
DISPLAY 0.978723 (-6325 5450);
PAINT SKYBLUE (-6325 5450);
DISPLAY INVISIBLE (-6325 5450);
FORCEPROP 1 LAST MATERIAL CHIP
J 0
(-6350 5550);
DISPLAY 0.489362 (-6350 5550);
PAINT SKYBLUE (-6350 5550);
DISPLAY INVISIBLE (-6350 5550);
FORCEPROP 1 LAST TOLERANCE 5%
J 0
(-6300 5500);
DISPLAY 0.978723 (-6300 5500);
PAINT SKYBLUE (-6300 5500);
DISPLAY INVISIBLE (-6300 5500);
FORCEPROP 1 LAST PART_NUMBER CS03302JB29
J 0
(-6350 5700);
DISPLAY 0.978723 (-6350 5700);
PAINT SKYBLUE (-6350 5700);
DISPLAY INVISIBLE (-6350 5700);
FORCEPROP 1 LAST PACK_TYPE 0402LF
J 0
(-6225 5550);
DISPLAY 0.489362 (-6225 5550);
PAINT SKYBLUE (-6225 5550);
DISPLAY INVISIBLE (-6225 5550);
FORCEADD GND..1
(-7000 5150);
FORCEPROP 3 LASTPIN (-7000 5200) SIG_NAME GND\g
J 0
(-6990 5210);
DISPLAY 0.659574 (-6990 5210);
PAINT MONO (-6990 5210);
DISPLAY INVISIBLE (-6990 5210);
FORCEPROP 1 LAST SIZE 1B
J 0
(-6925 5100);
DISPLAY 0.872340 (-6925 5100);
PAINT GREEN (-6925 5100);
DISPLAY INVISIBLE (-6925 5100);
FORCEPROP 2 LAST CDS_LIB pure_quanta_power
J 0
(-7000 5150);
DISPLAY INVISIBLE (-7000 5150);
FORCEPROP 1 LAST PATH I151
J 0
(-6925 5150);
DISPLAY 0.872340 (-6925 5150);
PAINT AQUA (-6925 5150);
DISPLAY INVISIBLE (-6925 5150);
FORCEPROP 1 LAST HDL_POWER GND
J 0
(-7000 5300);
DISPLAY 0.872340 (-7000 5300);
PAINT GREEN (-7000 5300);
DISPLAY INVISIBLE (-7000 5300);
FORCEADD Q_CAP..1
(-7000 5375);
FORCEPROP 1 LAST LOCATION C85
J 0
(-6950 5475);
DISPLAY 0.489362 (-6950 5475);
PAINT SKYBLUE (-6950 5475);
FORCEPROP 0 LAST $SEC 1
J 0
(-6950 5500);
DISPLAY 0.680851 (-6950 5500);
PAINT MONO (-6950 5500);
DISPLAY INVISIBLE (-6950 5500);
FORCEPROP 0 LAST CDS_SEC 1
J 0
(-6950 5500);
DISPLAY 0.680851 (-6950 5500);
DISPLAY INVISIBLE (-6950 5500);
FORCEPROP 1 LASTPIN (-7000 5475) $PN 1
J 0
(-6990 5455);
DISPLAY 0.489362 (-6990 5455);
PAINT MONO (-6990 5455);
FORCEPROP 1 LASTPIN (-7000 5275) $PN 2
J 0
(-6990 5255);
DISPLAY 0.489362 (-6990 5255);
PAINT MONO (-6990 5255);
FORCEPROP 1 LAST MATERIAL X7R
J 0
(-6950 5275);
DISPLAY 0.489362 (-6950 5275);
PAINT SKYBLUE (-6950 5275);
FORCEPROP 1 LAST TOLERANCE 10%
J 0
(-6950 5325);
DISPLAY 0.489362 (-6950 5325);
PAINT SKYBLUE (-6950 5325);
FORCEPROP 1 LAST VALUE 0.001UF
J 0
(-6950 5425);
DISPLAY 0.489362 (-6950 5425);
PAINT SKYBLUE (-6950 5425);
FORCEPROP 1 LAST VOLTAGE 50V
J 0
(-6950 5375);
DISPLAY 0.489362 (-6950 5375);
PAINT SKYBLUE (-6950 5375);
FORCEPROP 1 LAST PACK_TYPE C0402
J 0
(-6950 5225);
DISPLAY 0.489362 (-6950 5225);
PAINT SKYBLUE (-6950 5225);
FORCEPROP 2 LAST CDS_LIB pure_quanta
J 0
(-7000 5375);
DISPLAY INVISIBLE (-7000 5375);
FORCEPROP 1 LAST PATH I152
J 0
(-6950 5525);
DISPLAY 0.978723 (-6950 5525);
PAINT WHITE (-6950 5525);
DISPLAY INVISIBLE (-6950 5525);
FORCEPROP 1 LAST PART_NUMBER CH30106KB19
J 0
(-6950 5275);
DISPLAY 0.808511 (-6950 5275);
PAINT SKYBLUE (-6950 5275);
DISPLAY INVISIBLE (-6950 5275);
FORCEADD OFFPAGE..6
(-7125 5700);
FORCEPROP 2 LAST $XR1 81 
J 0
(-7494 5700);
DISPLAY 0.638298 (-7494 5700);
PAINT MONO (-7494 5700);
FORCEPROP 2 LAST $XR0 27 
J 0
(-7404 5700);
DISPLAY 0.638298 (-7404 5700);
PAINT MONO (-7404 5700);
FORCEPROP 2 LAST PATH I153
J 0
(-7350 5750);
DISPLAY 0.680851 (-7350 5750);
DISPLAY INVISIBLE (-7350 5750);
FORCEPROP 1 LAST COMMENT_BODY TRUE
J 0
(-7025 5625);
DISPLAY 0.872340 (-7025 5625);
PAINT GREEN (-7025 5625);
DISPLAY INVISIBLE (-7025 5625);
FORCEPROP 1 LAST OFFPAGE TRUE
J 0
(-6800 5575);
DISPLAY 0.872340 (-6800 5575);
PAINT GREEN (-6800 5575);
DISPLAY INVISIBLE (-6800 5575);
FORCEPROP 2 LAST CDS_LIB standard
J 0
(-7125 5700);
DISPLAY INVISIBLE (-7125 5700);
FORCEADD OFFPAGE..5
(-7150 5750);
FORCEPROP 2 LAST $XR0 149 
J 0
(-7405 5750);
DISPLAY 0.638298 (-7405 5750);
PAINT MONO (-7405 5750);
FORCEPROP 2 LAST PATH I154
J 0
(-7400 5800);
DISPLAY 0.680851 (-7400 5800);
DISPLAY INVISIBLE (-7400 5800);
FORCEPROP 1 LAST COMMENT_BODY TRUE
J 0
(-7050 5675);
DISPLAY 0.872340 (-7050 5675);
PAINT GREEN (-7050 5675);
DISPLAY INVISIBLE (-7050 5675);
FORCEPROP 1 LAST OFFPAGE TRUE
J 0
(-6825 5625);
DISPLAY 0.872340 (-6825 5625);
PAINT GREEN (-6825 5625);
DISPLAY INVISIBLE (-6825 5625);
FORCEPROP 2 LAST CDS_LIB standard
J 0
(-7150 5750);
DISPLAY INVISIBLE (-7150 5750);
FORCEADD OFFPAGE..6
(-7125 5650);
FORCEPROP 2 LAST $XR1 81 
J 0
(-7494 5650);
DISPLAY 0.638298 (-7494 5650);
PAINT MONO (-7494 5650);
FORCEPROP 2 LAST $XR0 27 
J 0
(-7404 5650);
DISPLAY 0.638298 (-7404 5650);
PAINT MONO (-7404 5650);
FORCEPROP 2 LAST PATH I155
J 0
(-7350 5700);
DISPLAY 0.680851 (-7350 5700);
DISPLAY INVISIBLE (-7350 5700);
FORCEPROP 1 LAST COMMENT_BODY TRUE
J 0
(-7025 5575);
DISPLAY 0.872340 (-7025 5575);
PAINT GREEN (-7025 5575);
DISPLAY INVISIBLE (-7025 5575);
FORCEPROP 1 LAST OFFPAGE TRUE
J 0
(-6800 5525);
DISPLAY 0.872340 (-6800 5525);
PAINT GREEN (-6800 5525);
DISPLAY INVISIBLE (-6800 5525);
FORCEPROP 2 LAST CDS_LIB standard
J 0
(-7125 5650);
DISPLAY INVISIBLE (-7125 5650);
FORCEADD OFFPAGE..6
(-7125 5600);
FORCEPROP 2 LAST $XR1 81 
J 0
(-7494 5600);
DISPLAY 0.638298 (-7494 5600);
PAINT MONO (-7494 5600);
FORCEPROP 2 LAST $XR0 27 
J 0
(-7404 5600);
DISPLAY 0.638298 (-7404 5600);
PAINT MONO (-7404 5600);
FORCEPROP 2 LAST PATH I156
J 0
(-7350 5650);
DISPLAY 0.680851 (-7350 5650);
DISPLAY INVISIBLE (-7350 5650);
FORCEPROP 1 LAST COMMENT_BODY TRUE
J 0
(-7025 5525);
DISPLAY 0.872340 (-7025 5525);
PAINT GREEN (-7025 5525);
DISPLAY INVISIBLE (-7025 5525);
FORCEPROP 1 LAST OFFPAGE TRUE
J 0
(-6800 5475);
DISPLAY 0.872340 (-6800 5475);
PAINT GREEN (-6800 5475);
DISPLAY INVISIBLE (-6800 5475);
FORCEPROP 2 LAST CDS_LIB standard
J 0
(-7125 5600);
DISPLAY INVISIBLE (-7125 5600);
FORCEADD Q_RES..1
(-6300 5900);
FORCEPROP 1 LAST LOCATION R1528
J 0
(-6525 5900);
DISPLAY 0.489362 (-6525 5900);
PAINT SKYBLUE (-6525 5900);
FORCEPROP 0 LAST $SEC 1
J 0
(-6125 5925);
DISPLAY 0.680851 (-6125 5925);
PAINT MONO (-6125 5925);
DISPLAY INVISIBLE (-6125 5925);
FORCEPROP 0 LAST CDS_SEC 1
J 0
(-6125 5925);
DISPLAY 0.680851 (-6125 5925);
DISPLAY INVISIBLE (-6125 5925);
FORCEPROP 1 LASTPIN (-6400 5900) $PN 1
J 0
(-6388 5912);
DISPLAY 0.489362 (-6388 5912);
PAINT MONO (-6388 5912);
FORCEPROP 1 LASTPIN (-6200 5900) $PN 2
J 0
(-6238 5912);
DISPLAY 0.489362 (-6238 5912);
PAINT MONO (-6238 5912);
FORCEPROP 1 LAST VALUE 33
J 2
(-6125 5900);
DISPLAY 0.489362 (-6125 5900);
PAINT SKYBLUE (-6125 5900);
FORCEPROP 2 LAST CDS_LIB pure_quanta
J 0
(-6300 5900);
DISPLAY INVISIBLE (-6300 5900);
FORCEPROP 1 LAST PATH I157
J 0
(-6350 6050);
DISPLAY 0.978723 (-6350 6050);
PAINT WHITE (-6350 6050);
DISPLAY INVISIBLE (-6350 6050);
FORCEPROP 1 LAST WATTAGE 1/16W
J 2
(-6325 5750);
DISPLAY 0.978723 (-6325 5750);
PAINT SKYBLUE (-6325 5750);
DISPLAY INVISIBLE (-6325 5750);
FORCEPROP 1 LAST MATERIAL CHIP
J 0
(-6350 5850);
DISPLAY 0.489362 (-6350 5850);
PAINT SKYBLUE (-6350 5850);
DISPLAY INVISIBLE (-6350 5850);
FORCEPROP 1 LAST TOLERANCE 5%
J 0
(-6300 5800);
DISPLAY 0.978723 (-6300 5800);
PAINT SKYBLUE (-6300 5800);
DISPLAY INVISIBLE (-6300 5800);
FORCEPROP 1 LAST PART_NUMBER CS03302JB29
J 0
(-6350 6000);
DISPLAY 0.978723 (-6350 6000);
PAINT SKYBLUE (-6350 6000);
DISPLAY INVISIBLE (-6350 6000);
FORCEPROP 1 LAST PACK_TYPE 0402LF
J 0
(-6225 5850);
DISPLAY 0.489362 (-6225 5850);
PAINT SKYBLUE (-6225 5850);
DISPLAY INVISIBLE (-6225 5850);
FORCEADD OFFPAGE..5
(-7150 5900);
FORCEPROP 2 LAST $XR1 80 
J 0
(-7494 5900);
DISPLAY 0.638298 (-7494 5900);
PAINT MONO (-7494 5900);
FORCEPROP 2 LAST $XR0 82 
J 0
(-7404 5900);
DISPLAY 0.638298 (-7404 5900);
PAINT MONO (-7404 5900);
FORCEPROP 2 LAST PATH I158
J 0
(-7100 5975);
DISPLAY 0.680851 (-7100 5975);
DISPLAY INVISIBLE (-7100 5975);
FORCEPROP 1 LAST COMMENT_BODY TRUE
J 0
(-7050 5825);
DISPLAY 0.872340 (-7050 5825);
PAINT GREEN (-7050 5825);
DISPLAY INVISIBLE (-7050 5825);
FORCEPROP 1 LAST OFFPAGE TRUE
J 0
(-6825 5775);
DISPLAY 0.872340 (-6825 5775);
PAINT GREEN (-6825 5775);
DISPLAY INVISIBLE (-6825 5775);
FORCEPROP 2 LAST CDS_LIB standard
J 0
(-7150 5900);
DISPLAY INVISIBLE (-7150 5900);
FORCEADD UNIVERSAL_POWER..1
(-3750 4825);
FORCEPROP 3 LASTPIN (-3750 4775) SIG_NAME PVDD18_S5_P0\g
J 0
(-3740 4785);
DISPLAY 0.659574 (-3740 4785);
PAINT MONO (-3740 4785);
DISPLAY INVISIBLE (-3740 4785);
FORCEPROP 1 LAST HDL_POWER PVDD18_S5_P0
J 1
(-3750 4875);
DISPLAY 0.489362 (-3750 4875);
PAINT GREEN (-3750 4875);
FORCEPROP 2 LAST CDS_LIB pure_quanta_power
J 0
(-3750 4825);
PAINT MONO (-3750 4825);
DISPLAY INVISIBLE (-3750 4825);
FORCEPROP 1 LAST PATH I20
J 0
(-3700 4850);
DISPLAY 0.872340 (-3700 4850);
PAINT AQUA (-3700 4850);
DISPLAY INVISIBLE (-3700 4850);
FORCEADD Q_CAP..1
(-800 3775);
FORCEPROP 1 LAST LOCATION C1512
J 0
(-750 3875);
DISPLAY 0.489362 (-750 3875);
PAINT SKYBLUE (-750 3875);
FORCEPROP 0 LAST $SEC 1
J 0
(-750 3925);
PAINT MONO (-750 3925);
DISPLAY INVISIBLE (-750 3925);
FORCEPROP 0 LAST CDS_SEC 1
J 0
(-750 3925);
PAINT MONO (-750 3925);
DISPLAY INVISIBLE (-750 3925);
FORCEPROP 1 LASTPIN (-800 3875) $PN 1
J 0
(-790 3855);
DISPLAY 0.489362 (-790 3855);
PAINT GREEN (-790 3855);
FORCEPROP 1 LASTPIN (-800 3675) $PN 2
J 0
(-790 3655);
DISPLAY 0.489362 (-790 3655);
PAINT GREEN (-790 3655);
FORCEPROP 1 LAST MATERIAL NPO
J 0
(-750 3475);
DISPLAY 0.489362 (-750 3475);
PAINT SKYBLUE (-750 3475);
FORCEPROP 1 LAST TOLERANCE 5%
J 0
(-750 3725);
DISPLAY 0.489362 (-750 3725);
PAINT SKYBLUE (-750 3725);
FORCEPROP 1 LAST VALUE 33PF
J 0
(-750 3825);
DISPLAY 0.489362 (-750 3825);
PAINT SKYBLUE (-750 3825);
FORCEPROP 1 LAST PART_NUMBER TMP_QCH03306JB04
J 0
(-750 3675);
DISPLAY 0.489362 (-750 3675);
PAINT SKYBLUE (-750 3675);
FORCEPROP 1 LAST VOLTAGE 50V
J 0
(-750 3775);
DISPLAY 0.489362 (-750 3775);
PAINT SKYBLUE (-750 3775);
FORCEPROP 1 LAST PACK_TYPE 0402
J 0
(-750 3625);
DISPLAY 0.489362 (-750 3625);
PAINT SKYBLUE (-750 3625);
FORCEPROP 2 LAST CDS_LIB pure_quanta
J 0
(-800 3775);
PAINT MONO (-800 3775);
DISPLAY INVISIBLE (-800 3775);
FORCEPROP 1 LAST PATH I21
J 0
(-750 3925);
DISPLAY 0.978723 (-750 3925);
PAINT WHITE (-750 3925);
DISPLAY INVISIBLE (-750 3925);
FORCEADD GND..1
(-800 3450);
FORCEPROP 3 LASTPIN (-800 3500) SIG_NAME GND\g
J 0
(-790 3510);
DISPLAY 0.659574 (-790 3510);
PAINT MONO (-790 3510);
DISPLAY INVISIBLE (-790 3510);
FORCEPROP 2 LAST CDS_LIB pure_quanta_power
J 0
(-800 3450);
DISPLAY INVISIBLE (-800 3450);
FORCEPROP 1 LAST SIZE 1B
J 0
(-725 3400);
DISPLAY 0.872340 (-725 3400);
PAINT GREEN (-725 3400);
DISPLAY INVISIBLE (-725 3400);
FORCEPROP 1 LAST PATH I22
J 0
(-725 3450);
DISPLAY 0.872340 (-725 3450);
PAINT AQUA (-725 3450);
DISPLAY INVISIBLE (-725 3450);
FORCEPROP 1 LAST HDL_POWER GND
J 0
(-800 3600);
DISPLAY 0.872340 (-800 3600);
PAINT GREEN (-800 3600);
DISPLAY INVISIBLE (-800 3600);
FORCEADD Q_CAP..1
(-1125 3775);
FORCEPROP 1 LAST LOCATION C1511
J 0
(-1075 3875);
DISPLAY 0.489362 (-1075 3875);
PAINT SKYBLUE (-1075 3875);
FORCEPROP 0 LAST $SEC 1
J 0
(-1075 3925);
PAINT MONO (-1075 3925);
DISPLAY INVISIBLE (-1075 3925);
FORCEPROP 0 LAST CDS_SEC 1
J 0
(-1075 3925);
PAINT MONO (-1075 3925);
DISPLAY INVISIBLE (-1075 3925);
FORCEPROP 1 LASTPIN (-1125 3875) $PN 1
J 0
(-1115 3855);
DISPLAY 0.489362 (-1115 3855);
PAINT GREEN (-1115 3855);
FORCEPROP 1 LASTPIN (-1125 3675) $PN 2
J 0
(-1115 3655);
DISPLAY 0.489362 (-1115 3655);
PAINT GREEN (-1115 3655);
FORCEPROP 1 LAST MATERIAL NPO
J 0
(-1075 3475);
DISPLAY 0.489362 (-1075 3475);
PAINT SKYBLUE (-1075 3475);
FORCEPROP 1 LAST TOLERANCE 5%
J 0
(-1075 3725);
DISPLAY 0.489362 (-1075 3725);
PAINT SKYBLUE (-1075 3725);
FORCEPROP 1 LAST VALUE 33PF
J 0
(-1075 3825);
DISPLAY 0.489362 (-1075 3825);
PAINT SKYBLUE (-1075 3825);
FORCEPROP 1 LAST VOLTAGE 50V
J 0
(-1075 3775);
DISPLAY 0.489362 (-1075 3775);
PAINT SKYBLUE (-1075 3775);
FORCEPROP 1 LAST PACK_TYPE 0402
J 0
(-1075 3625);
DISPLAY 0.489362 (-1075 3625);
PAINT SKYBLUE (-1075 3625);
FORCEPROP 2 LAST CDS_LIB pure_quanta
J 0
(-1125 3775);
PAINT MONO (-1125 3775);
DISPLAY INVISIBLE (-1125 3775);
FORCEPROP 1 LAST PATH I23
J 0
(-1075 3925);
DISPLAY 0.978723 (-1075 3925);
PAINT WHITE (-1075 3925);
DISPLAY INVISIBLE (-1075 3925);
FORCEPROP 1 LAST PART_NUMBER TMP_QCH03306JB04
J 0
(-1075 3675);
DISPLAY 0.808511 (-1075 3675);
PAINT SKYBLUE (-1075 3675);
DISPLAY INVISIBLE (-1075 3675);
FORCEADD GND..1
(-1125 3450);
FORCEPROP 3 LASTPIN (-1125 3500) SIG_NAME GND\g
J 0
(-1115 3510);
DISPLAY 0.659574 (-1115 3510);
PAINT MONO (-1115 3510);
DISPLAY INVISIBLE (-1115 3510);
FORCEPROP 2 LAST CDS_LIB pure_quanta_power
J 0
(-1125 3450);
DISPLAY INVISIBLE (-1125 3450);
FORCEPROP 1 LAST SIZE 1B
J 0
(-1050 3400);
DISPLAY 0.872340 (-1050 3400);
PAINT GREEN (-1050 3400);
DISPLAY INVISIBLE (-1050 3400);
FORCEPROP 1 LAST PATH I24
J 0
(-1050 3450);
DISPLAY 0.872340 (-1050 3450);
PAINT AQUA (-1050 3450);
DISPLAY INVISIBLE (-1050 3450);
FORCEPROP 1 LAST HDL_POWER GND
J 0
(-1125 3600);
DISPLAY 0.872340 (-1125 3600);
PAINT GREEN (-1125 3600);
DISPLAY INVISIBLE (-1125 3600);
FORCEADD Q_CAP..1
(-1500 3775);
FORCEPROP 1 LAST LOCATION C1510
J 0
(-1450 3875);
DISPLAY 0.489362 (-1450 3875);
PAINT SKYBLUE (-1450 3875);
FORCEPROP 0 LAST $SEC 1
J 0
(-1450 3925);
PAINT MONO (-1450 3925);
DISPLAY INVISIBLE (-1450 3925);
FORCEPROP 0 LAST CDS_SEC 1
J 0
(-1450 3925);
PAINT MONO (-1450 3925);
DISPLAY INVISIBLE (-1450 3925);
FORCEPROP 1 LASTPIN (-1500 3875) $PN 1
J 0
(-1490 3855);
DISPLAY 0.489362 (-1490 3855);
PAINT GREEN (-1490 3855);
FORCEPROP 1 LASTPIN (-1500 3675) $PN 2
J 0
(-1490 3655);
DISPLAY 0.489362 (-1490 3655);
PAINT GREEN (-1490 3655);
FORCEPROP 1 LAST MATERIAL NPO
J 0
(-1450 3475);
DISPLAY 0.489362 (-1450 3475);
PAINT SKYBLUE (-1450 3475);
FORCEPROP 1 LAST TOLERANCE 5%
J 0
(-1450 3725);
DISPLAY 0.489362 (-1450 3725);
PAINT SKYBLUE (-1450 3725);
FORCEPROP 1 LAST VALUE 33PF
J 0
(-1450 3825);
DISPLAY 0.489362 (-1450 3825);
PAINT SKYBLUE (-1450 3825);
FORCEPROP 1 LAST VOLTAGE 50V
J 0
(-1450 3775);
DISPLAY 0.489362 (-1450 3775);
PAINT SKYBLUE (-1450 3775);
FORCEPROP 1 LAST PACK_TYPE 0402
J 0
(-1450 3625);
DISPLAY 0.489362 (-1450 3625);
PAINT SKYBLUE (-1450 3625);
FORCEPROP 2 LAST CDS_LIB pure_quanta
J 0
(-1500 3775);
PAINT MONO (-1500 3775);
DISPLAY INVISIBLE (-1500 3775);
FORCEPROP 1 LAST PATH I25
J 0
(-1450 3925);
DISPLAY 0.978723 (-1450 3925);
PAINT WHITE (-1450 3925);
DISPLAY INVISIBLE (-1450 3925);
FORCEPROP 1 LAST PART_NUMBER TMP_QCH03306JB04
J 0
(-1450 3675);
DISPLAY 0.808511 (-1450 3675);
PAINT SKYBLUE (-1450 3675);
DISPLAY INVISIBLE (-1450 3675);
FORCEADD GND..1
(-1500 3450);
FORCEPROP 3 LASTPIN (-1500 3500) SIG_NAME GND\g
J 0
(-1490 3510);
DISPLAY 0.659574 (-1490 3510);
PAINT MONO (-1490 3510);
DISPLAY INVISIBLE (-1490 3510);
FORCEPROP 1 LAST SIZE 1B
J 0
(-1425 3400);
DISPLAY 0.872340 (-1425 3400);
PAINT GREEN (-1425 3400);
DISPLAY INVISIBLE (-1425 3400);
FORCEPROP 2 LAST CDS_LIB pure_quanta_power
J 0
(-1500 3450);
DISPLAY INVISIBLE (-1500 3450);
FORCEPROP 1 LAST PATH I26
J 0
(-1425 3450);
DISPLAY 0.872340 (-1425 3450);
PAINT AQUA (-1425 3450);
DISPLAY INVISIBLE (-1425 3450);
FORCEPROP 1 LAST HDL_POWER GND
J 0
(-1500 3600);
DISPLAY 0.872340 (-1500 3600);
PAINT GREEN (-1500 3600);
DISPLAY INVISIBLE (-1500 3600);
FORCEADD GND..1
(-2700 3500);
FORCEPROP 3 LASTPIN (-2700 3550) SIG_NAME GND\g
J 0
(-2690 3560);
DISPLAY 0.659574 (-2690 3560);
PAINT MONO (-2690 3560);
DISPLAY INVISIBLE (-2690 3560);
FORCEPROP 2 LAST CDS_LIB pure_quanta_power
J 0
(-2700 3500);
PAINT MONO (-2700 3500);
DISPLAY INVISIBLE (-2700 3500);
FORCEPROP 1 LAST SIZE 1B
J 0
(-2625 3450);
DISPLAY 0.872340 (-2625 3450);
PAINT GREEN (-2625 3450);
DISPLAY INVISIBLE (-2625 3450);
FORCEPROP 1 LAST PATH I27
J 0
(-2625 3500);
DISPLAY 0.872340 (-2625 3500);
PAINT AQUA (-2625 3500);
DISPLAY INVISIBLE (-2625 3500);
FORCEPROP 1 LAST HDL_POWER GND
J 0
(-2700 3650);
DISPLAY 0.872340 (-2700 3650);
PAINT GREEN (-2700 3650);
DISPLAY INVISIBLE (-2700 3650);
FORCEADD UNIVERSAL_POWER..1
(-2725 2950);
FORCEPROP 3 LASTPIN (-2725 2900) SIG_NAME PVDD18_S5_P0\g
J 0
(-2715 2910);
DISPLAY 0.659574 (-2715 2910);
PAINT MONO (-2715 2910);
DISPLAY INVISIBLE (-2715 2910);
FORCEPROP 1 LAST HDL_POWER PVDD18_S5_P0
J 1
(-2725 3000);
DISPLAY 0.489362 (-2725 3000);
PAINT GREEN (-2725 3000);
FORCEPROP 2 LAST CDS_LIB pure_quanta_power
J 0
(-2725 2950);
PAINT MONO (-2725 2950);
DISPLAY INVISIBLE (-2725 2950);
FORCEPROP 1 LAST PATH I28
J 0
(-2675 2975);
DISPLAY 0.872340 (-2675 2975);
PAINT AQUA (-2675 2975);
DISPLAY INVISIBLE (-2675 2975);
FORCEADD Q_CAP..1
(-2650 2650);
FORCEPROP 1 LAST LOCATION C1508
J 0
(-2550 2800);
DISPLAY 0.489362 (-2550 2800);
PAINT SKYBLUE (-2550 2800);
FORCEPROP 2 LAST $SEC 1
J 0
(-2600 2850);
PAINT MONO (-2600 2850);
DISPLAY INVISIBLE (-2600 2850);
FORCEPROP 2 LAST CDS_SEC 1
J 0
(-2600 2850);
PAINT MONO (-2600 2850);
DISPLAY INVISIBLE (-2600 2850);
FORCEPROP 1 LASTPIN (-2650 2750) $PN 1
J 0
(-2640 2730);
DISPLAY 0.489362 (-2640 2730);
PAINT GREEN (-2640 2730);
FORCEPROP 1 LASTPIN (-2650 2550) $PN 2
J 0
(-2640 2530);
DISPLAY 0.489362 (-2640 2530);
PAINT GREEN (-2640 2530);
FORCEPROP 1 LAST MATERIAL X7R
J 0
(-2550 2600);
DISPLAY 0.489362 (-2550 2600);
PAINT SKYBLUE (-2550 2600);
FORCEPROP 1 LAST TOLERANCE 10%
J 0
(-2550 2650);
DISPLAY 0.489362 (-2550 2650);
PAINT SKYBLUE (-2550 2650);
FORCEPROP 1 LAST VALUE 0.1UF
J 0
(-2550 2750);
DISPLAY 0.489362 (-2550 2750);
PAINT SKYBLUE (-2550 2750);
FORCEPROP 1 LAST PART_NUMBER CH4103K1B08
J 0
(-2550 2550);
DISPLAY 0.489362 (-2550 2550);
PAINT SKYBLUE (-2550 2550);
FORCEPROP 1 LAST VOLTAGE 16V
J 0
(-2550 2700);
DISPLAY 0.489362 (-2550 2700);
PAINT SKYBLUE (-2550 2700);
FORCEPROP 1 LAST PACK_TYPE C0402
J 0
(-2550 2500);
DISPLAY 0.489362 (-2550 2500);
PAINT SKYBLUE (-2550 2500);
FORCEPROP 2 LAST CDS_LIB pure_quanta
J 0
(-2650 2650);
DISPLAY INVISIBLE (-2650 2650);
FORCEPROP 1 LAST PATH I29
J 0
(-2600 2800);
DISPLAY 0.978723 (-2600 2800);
PAINT WHITE (-2600 2800);
DISPLAY INVISIBLE (-2600 2800);
FORCEADD OFFPAGE..2
(-525 4225);
FORCEPROP 2 LAST $XR0 150 
J 0
(-336 4225);
DISPLAY 0.638298 (-336 4225);
PAINT MONO (-336 4225);
FORCEPROP 2 LAST PATH I3
J 0
(-325 4275);
DISPLAY 1.021277 (-325 4275);
DISPLAY INVISIBLE (-325 4275);
FORCEPROP 1 LAST COMMENT_BODY TRUE
J 0
(-570 4130);
DISPLAY 0.872340 (-570 4130);
PAINT GREEN (-570 4130);
DISPLAY INVISIBLE (-570 4130);
FORCEPROP 1 LAST OFFPAGE TRUE
J 0
(-200 4100);
DISPLAY 0.872340 (-200 4100);
PAINT GREEN (-200 4100);
DISPLAY INVISIBLE (-200 4100);
FORCEPROP 2 LAST CDS_LIB standard
J 0
(-525 4225);
PAINT MONO (-525 4225);
DISPLAY INVISIBLE (-525 4225);
FORCEADD GND..1
(-2650 2475);
FORCEPROP 3 LASTPIN (-2650 2525) SIG_NAME GND\g
J 0
(-2640 2535);
DISPLAY 0.659574 (-2640 2535);
PAINT MONO (-2640 2535);
DISPLAY INVISIBLE (-2640 2535);
FORCEPROP 1 LAST SIZE 1B
J 0
(-2575 2425);
DISPLAY 0.872340 (-2575 2425);
PAINT GREEN (-2575 2425);
DISPLAY INVISIBLE (-2575 2425);
FORCEPROP 2 LAST CDS_LIB pure_quanta_power
J 0
(-2650 2475);
DISPLAY INVISIBLE (-2650 2475);
FORCEPROP 1 LAST PATH I30
J 0
(-2575 2475);
DISPLAY 0.872340 (-2575 2475);
PAINT AQUA (-2575 2475);
DISPLAY INVISIBLE (-2575 2475);
FORCEPROP 1 LAST HDL_POWER GND
J 0
(-2650 2625);
DISPLAY 0.872340 (-2650 2625);
PAINT GREEN (-2650 2625);
DISPLAY INVISIBLE (-2650 2625);
FORCEADD SN74AVC4T774PWR..1
(-3225 4075);
FORCEPROP 1 LAST LOCATION U149
J 0
(-3472 4640);
DISPLAY 0.489362 (-3472 4640);
PAINT SKYBLUE (-3472 4640);
FORCEPROP 0 LAST $SEC 1
J 0
(-3450 4775);
PAINT MONO (-3450 4775);
DISPLAY INVISIBLE (-3450 4775);
FORCEPROP 0 LAST CDS_SEC 1
J 0
(-3450 4775);
PAINT MONO (-3450 4775);
DISPLAY INVISIBLE (-3450 4775);
FORCEPROP 0 LASTPIN (-3625 4225) $PN 3
J 2
(-3635 4235);
DISPLAY 0.489362 (-3635 4235);
PAINT MONO (-3635 4235);
FORCEPROP 0 LASTPIN (-3625 4175) $PN 4
J 2
(-3635 4185);
DISPLAY 0.489362 (-3635 4185);
PAINT MONO (-3635 4185);
FORCEPROP 0 LASTPIN (-3625 4125) $PN 5
J 2
(-3635 4135);
DISPLAY 0.489362 (-3635 4135);
PAINT MONO (-3635 4135);
FORCEPROP 0 LASTPIN (-3625 4075) $PN 6
J 2
(-3635 4085);
DISPLAY 0.489362 (-3635 4085);
PAINT MONO (-3635 4085);
FORCEPROP 0 LASTPIN (-2825 4225) $PN 14
J 0
(-2815 4235);
DISPLAY 0.489362 (-2815 4235);
PAINT MONO (-2815 4235);
FORCEPROP 0 LASTPIN (-2825 4175) $PN 13
J 0
(-2815 4185);
DISPLAY 0.489362 (-2815 4185);
PAINT MONO (-2815 4185);
FORCEPROP 0 LASTPIN (-2825 4125) $PN 12
J 0
(-2815 4135);
DISPLAY 0.489362 (-2815 4135);
PAINT MONO (-2815 4135);
FORCEPROP 0 LASTPIN (-2825 4075) $PN 11
J 0
(-2815 4085);
DISPLAY 0.489362 (-2815 4085);
PAINT MONO (-2815 4085);
FORCEPROP 0 LASTPIN (-3625 3925) $PN 1
J 2
(-3635 3935);
DISPLAY 0.489362 (-3635 3935);
PAINT MONO (-3635 3935);
FORCEPROP 0 LASTPIN (-3625 3875) $PN 2
J 2
(-3635 3885);
DISPLAY 0.489362 (-3635 3885);
PAINT MONO (-3635 3885);
FORCEPROP 0 LASTPIN (-3625 3825) $PN 7
J 2
(-3635 3835);
DISPLAY 0.489362 (-3635 3835);
PAINT MONO (-3635 3835);
FORCEPROP 0 LASTPIN (-3625 3775) $PN 8
J 2
(-3635 3785);
DISPLAY 0.489362 (-3635 3785);
PAINT MONO (-3635 3785);
FORCEPROP 0 LASTPIN (-2825 3675) $PN 10
J 0
(-2815 3685);
DISPLAY 0.489362 (-2815 3685);
PAINT MONO (-2815 3685);
FORCEPROP 0 LASTPIN (-3625 3725) $PN 9
J 2
(-3635 3735);
DISPLAY 0.489362 (-3635 3735);
PAINT MONO (-3635 3735);
FORCEPROP 0 LASTPIN (-3625 4425) $PN 16
J 2
(-3635 4435);
DISPLAY 0.489362 (-3635 4435);
PAINT MONO (-3635 4435);
FORCEPROP 0 LASTPIN (-2825 4425) $PN 15
J 0
(-2815 4435);
DISPLAY 0.489362 (-2815 4435);
PAINT MONO (-2815 4435);
FORCEPROP 1 LAST MATERIAL IC
J 0
(-3472 4528);
DISPLAY 0.489362 (-3472 4528);
PAINT SKYBLUE (-3472 4528);
FORCEPROP 2 LAST VALUE SN74AVC4T774PWR
J 0
(-3475 4700);
DISPLAY 0.489362 (-3475 4700);
PAINT SKYBLUE (-3475 4700);
FORCEPROP 1 LAST PART_NUMBER AL04T774K00
J 0
(-3472 4583);
DISPLAY 0.489362 (-3472 4583);
PAINT SKYBLUE (-3472 4583);
FORCEPROP 2 LAST PART_TYPE SMLF
J 0
(-3475 4775);
PAINT MONO (-3475 4775);
FORCEPROP 2 LAST CDS_LIB pure_quanta
J 0
(-3225 4075);
PAINT MONO (-3225 4075);
DISPLAY INVISIBLE (-3225 4075);
FORCEPROP 1 LAST NEEDS_NO_SIZE TRUE
J 0
(-3225 4075);
DISPLAY 0.723404 (-3225 4075);
PAINT GREEN (-3225 4075);
DISPLAY INVISIBLE (-3225 4075);
FORCEPROP 1 LAST CDS_LMAN_SYM_OUTLINE -250,450,250,-450
J 0
(-3225 4075);
DISPLAY 0.468085 (-3225 4075);
PAINT GREEN (-3225 4075);
DISPLAY INVISIBLE (-3225 4075);
FORCEPROP 1 LAST PATH I31
J 0
(-3225 4075);
DISPLAY 0.723404 (-3225 4075);
PAINT GREEN (-3225 4075);
DISPLAY INVISIBLE (-3225 4075);
FORCEADD UNIVERSAL_POWER..1
(-3750 2675);
FORCEPROP 3 LASTPIN (-3750 2625) SIG_NAME P3V3_STBY\g
J 0
(-3740 2635);
DISPLAY 0.659574 (-3740 2635);
PAINT MONO (-3740 2635);
DISPLAY INVISIBLE (-3740 2635);
FORCEPROP 1 LAST HDL_POWER P3V3_STBY
J 1
(-3750 2725);
DISPLAY 0.489362 (-3750 2725);
PAINT GREEN (-3750 2725);
FORCEPROP 2 LAST CDS_LIB pure_quanta_power
J 0
(-3750 2675);
PAINT MONO (-3750 2675);
DISPLAY INVISIBLE (-3750 2675);
FORCEPROP 1 LAST PATH I32
J 0
(-3700 2700);
DISPLAY 0.872340 (-3700 2700);
PAINT AQUA (-3700 2700);
DISPLAY INVISIBLE (-3700 2700);
FORCEADD GND..1
(-2725 1350);
FORCEPROP 3 LASTPIN (-2725 1400) SIG_NAME GND\g
J 0
(-2715 1410);
DISPLAY 0.659574 (-2715 1410);
PAINT MONO (-2715 1410);
DISPLAY INVISIBLE (-2715 1410);
FORCEPROP 1 LAST SIZE 1B
J 0
(-2650 1300);
DISPLAY 0.872340 (-2650 1300);
PAINT GREEN (-2650 1300);
DISPLAY INVISIBLE (-2650 1300);
FORCEPROP 2 LAST CDS_LIB pure_quanta_power
J 0
(-2725 1350);
PAINT MONO (-2725 1350);
DISPLAY INVISIBLE (-2725 1350);
FORCEPROP 1 LAST PATH I33
J 0
(-2650 1350);
DISPLAY 0.872340 (-2650 1350);
PAINT AQUA (-2650 1350);
DISPLAY INVISIBLE (-2650 1350);
FORCEPROP 1 LAST HDL_POWER GND
J 0
(-2725 1500);
DISPLAY 0.872340 (-2725 1500);
PAINT GREEN (-2725 1500);
DISPLAY INVISIBLE (-2725 1500);
FORCEADD SN74AVC4T774PWR..1
(-3250 1925);
FORCEPROP 1 LAST LOCATION U148
J 0
(-3497 2490);
DISPLAY 0.489362 (-3497 2490);
PAINT SKYBLUE (-3497 2490);
FORCEPROP 0 LAST $SEC 1
J 0
(-3475 2625);
PAINT MONO (-3475 2625);
DISPLAY INVISIBLE (-3475 2625);
FORCEPROP 0 LAST CDS_SEC 1
J 0
(-3475 2625);
PAINT MONO (-3475 2625);
DISPLAY INVISIBLE (-3475 2625);
FORCEPROP 0 LASTPIN (-3650 2075) $PN 3
J 2
(-3660 2085);
DISPLAY 0.489362 (-3660 2085);
PAINT MONO (-3660 2085);
FORCEPROP 0 LASTPIN (-3650 2025) $PN 4
J 2
(-3660 2035);
DISPLAY 0.489362 (-3660 2035);
PAINT MONO (-3660 2035);
FORCEPROP 0 LASTPIN (-3650 1975) $PN 5
J 2
(-3660 1985);
DISPLAY 0.489362 (-3660 1985);
PAINT MONO (-3660 1985);
FORCEPROP 0 LASTPIN (-3650 1925) $PN 6
J 2
(-3660 1935);
DISPLAY 0.489362 (-3660 1935);
PAINT MONO (-3660 1935);
FORCEPROP 0 LASTPIN (-2850 2075) $PN 14
J 0
(-2840 2085);
DISPLAY 0.489362 (-2840 2085);
PAINT MONO (-2840 2085);
FORCEPROP 0 LASTPIN (-2850 2025) $PN 13
J 0
(-2840 2035);
DISPLAY 0.489362 (-2840 2035);
PAINT MONO (-2840 2035);
FORCEPROP 0 LASTPIN (-2850 1975) $PN 12
J 0
(-2840 1985);
DISPLAY 0.489362 (-2840 1985);
PAINT MONO (-2840 1985);
FORCEPROP 0 LASTPIN (-2850 1925) $PN 11
J 0
(-2840 1935);
DISPLAY 0.489362 (-2840 1935);
PAINT MONO (-2840 1935);
FORCEPROP 0 LASTPIN (-3650 1775) $PN 1
J 2
(-3660 1785);
DISPLAY 0.489362 (-3660 1785);
PAINT MONO (-3660 1785);
FORCEPROP 0 LASTPIN (-3650 1725) $PN 2
J 2
(-3660 1735);
DISPLAY 0.489362 (-3660 1735);
PAINT MONO (-3660 1735);
FORCEPROP 0 LASTPIN (-3650 1675) $PN 7
J 2
(-3660 1685);
DISPLAY 0.489362 (-3660 1685);
PAINT MONO (-3660 1685);
FORCEPROP 0 LASTPIN (-3650 1625) $PN 8
J 2
(-3660 1635);
DISPLAY 0.489362 (-3660 1635);
PAINT MONO (-3660 1635);
FORCEPROP 0 LASTPIN (-2850 1525) $PN 10
J 0
(-2840 1535);
DISPLAY 0.489362 (-2840 1535);
PAINT MONO (-2840 1535);
FORCEPROP 0 LASTPIN (-3650 1575) $PN 9
J 2
(-3660 1585);
DISPLAY 0.489362 (-3660 1585);
PAINT MONO (-3660 1585);
FORCEPROP 0 LASTPIN (-3650 2275) $PN 16
J 2
(-3660 2285);
DISPLAY 0.489362 (-3660 2285);
PAINT MONO (-3660 2285);
FORCEPROP 0 LASTPIN (-2850 2275) $PN 15
J 0
(-2840 2285);
DISPLAY 0.489362 (-2840 2285);
PAINT MONO (-2840 2285);
FORCEPROP 2 LAST PART_TYPE SMLF
J 0
(-3500 2625);
PAINT MONO (-3500 2625);
FORCEPROP 1 LAST MATERIAL IC
J 0
(-3497 2378);
DISPLAY 0.489362 (-3497 2378);
PAINT SKYBLUE (-3497 2378);
FORCEPROP 1 LAST PART_NUMBER AL04T774K00
J 0
(-3497 2433);
DISPLAY 0.489362 (-3497 2433);
PAINT SKYBLUE (-3497 2433);
FORCEPROP 2 LAST VALUE SN74AVC4T774PWR
J 0
(-3500 2550);
DISPLAY 0.489362 (-3500 2550);
PAINT SKYBLUE (-3500 2550);
FORCEPROP 1 LAST CDS_LMAN_SYM_OUTLINE -250,450,250,-450
J 0
(-3250 1925);
DISPLAY 0.468085 (-3250 1925);
PAINT GREEN (-3250 1925);
DISPLAY INVISIBLE (-3250 1925);
FORCEPROP 2 LAST CDS_LIB pure_quanta
J 0
(-3250 1925);
PAINT MONO (-3250 1925);
DISPLAY INVISIBLE (-3250 1925);
FORCEPROP 1 LAST NEEDS_NO_SIZE TRUE
J 0
(-3250 1925);
DISPLAY 0.723404 (-3250 1925);
PAINT GREEN (-3250 1925);
DISPLAY INVISIBLE (-3250 1925);
FORCEPROP 1 LAST PATH I34
J 0
(-3250 1925);
DISPLAY 0.723404 (-3250 1925);
PAINT GREEN (-3250 1925);
DISPLAY INVISIBLE (-3250 1925);
FORCEADD OFFPAGE..2
(-525 4175);
FORCEPROP 2 LAST $XR0 150 
J 0
(-336 4175);
DISPLAY 0.638298 (-336 4175);
PAINT MONO (-336 4175);
FORCEPROP 2 LAST PATH I4
J 0
(-325 4225);
DISPLAY 1.021277 (-325 4225);
DISPLAY INVISIBLE (-325 4225);
FORCEPROP 1 LAST COMMENT_BODY TRUE
J 0
(-570 4080);
DISPLAY 0.872340 (-570 4080);
PAINT GREEN (-570 4080);
DISPLAY INVISIBLE (-570 4080);
FORCEPROP 1 LAST OFFPAGE TRUE
J 0
(-200 4050);
DISPLAY 0.872340 (-200 4050);
PAINT GREEN (-200 4050);
DISPLAY INVISIBLE (-200 4050);
FORCEPROP 2 LAST CDS_LIB standard
J 0
(-525 4175);
PAINT MONO (-525 4175);
DISPLAY INVISIBLE (-525 4175);
FORCEADD Q_CAP..1
(-3975 4550);
FORCEPROP 1 LAST LOCATION C1507
J 0
(-4125 4675);
DISPLAY 0.489362 (-4125 4675);
PAINT SKYBLUE (-4125 4675);
FORCEPROP 2 LAST $SEC 1
J 0
(-3925 4750);
PAINT MONO (-3925 4750);
DISPLAY INVISIBLE (-3925 4750);
FORCEPROP 2 LAST CDS_SEC 1
J 0
(-3925 4750);
PAINT MONO (-3925 4750);
DISPLAY INVISIBLE (-3925 4750);
FORCEPROP 1 LASTPIN (-3975 4650) $PN 1
J 0
(-3965 4630);
DISPLAY 0.489362 (-3965 4630);
PAINT GREEN (-3965 4630);
FORCEPROP 1 LASTPIN (-3975 4450) $PN 2
J 0
(-3965 4430);
DISPLAY 0.489362 (-3965 4430);
PAINT GREEN (-3965 4430);
FORCEPROP 1 LAST MATERIAL X7R
J 0
(-4100 4475);
DISPLAY 0.489362 (-4100 4475);
PAINT SKYBLUE (-4100 4475);
FORCEPROP 1 LAST TOLERANCE 10%
J 0
(-4100 4525);
DISPLAY 0.489362 (-4100 4525);
PAINT SKYBLUE (-4100 4525);
FORCEPROP 1 LAST VALUE 0.1UF
J 0
(-4150 4625);
DISPLAY 0.489362 (-4150 4625);
PAINT SKYBLUE (-4150 4625);
FORCEPROP 1 LAST PART_NUMBER CH4103K1B08
J 0
(-4325 4425);
DISPLAY 0.489362 (-4325 4425);
PAINT SKYBLUE (-4325 4425);
FORCEPROP 1 LAST VOLTAGE 16V
J 0
(-4100 4575);
DISPLAY 0.489362 (-4100 4575);
PAINT SKYBLUE (-4100 4575);
FORCEPROP 1 LAST PACK_TYPE C0402
J 0
(-4150 4375);
DISPLAY 0.489362 (-4150 4375);
PAINT SKYBLUE (-4150 4375);
FORCEPROP 2 LAST CDS_LIB pure_quanta
J 0
(-3975 4550);
DISPLAY INVISIBLE (-3975 4550);
FORCEPROP 1 LAST PATH I41
J 0
(-3925 4700);
DISPLAY 0.978723 (-3925 4700);
PAINT WHITE (-3925 4700);
DISPLAY INVISIBLE (-3925 4700);
FORCEADD GND..1
(-3975 4375);
FORCEPROP 3 LASTPIN (-3975 4425) SIG_NAME GND\g
J 0
(-3965 4435);
DISPLAY 0.659574 (-3965 4435);
PAINT MONO (-3965 4435);
DISPLAY INVISIBLE (-3965 4435);
FORCEPROP 1 LAST SIZE 1B
J 0
(-3900 4325);
DISPLAY 0.872340 (-3900 4325);
PAINT GREEN (-3900 4325);
DISPLAY INVISIBLE (-3900 4325);
FORCEPROP 2 LAST CDS_LIB pure_quanta_power
J 0
(-3975 4375);
DISPLAY INVISIBLE (-3975 4375);
FORCEPROP 1 LAST PATH I42
J 0
(-3900 4375);
DISPLAY 0.872340 (-3900 4375);
PAINT AQUA (-3900 4375);
DISPLAY INVISIBLE (-3900 4375);
FORCEPROP 1 LAST HDL_POWER GND
J 0
(-3975 4525);
DISPLAY 0.872340 (-3975 4525);
PAINT GREEN (-3975 4525);
DISPLAY INVISIBLE (-3975 4525);
FORCEADD OFFPAGE..1
(-4375 4225);
FORCEPROP 2 LAST $XR0 149 
J 0
(-4627 4225);
DISPLAY 0.638298 (-4627 4225);
PAINT MONO (-4627 4225);
FORCEPROP 2 LAST PATH I43
J 0
(-4575 4275);
DISPLAY 1.021277 (-4575 4275);
DISPLAY INVISIBLE (-4575 4275);
FORCEPROP 1 LAST COMMENT_BODY TRUE
J 0
(-4250 4125);
DISPLAY 0.872340 (-4250 4125);
PAINT GREEN (-4250 4125);
DISPLAY INVISIBLE (-4250 4125);
FORCEPROP 1 LAST OFFPAGE TRUE
J 0
(-4050 4100);
DISPLAY 0.872340 (-4050 4100);
PAINT GREEN (-4050 4100);
DISPLAY INVISIBLE (-4050 4100);
FORCEPROP 2 LAST CDS_LIB standard
J 0
(-4375 4225);
PAINT MONO (-4375 4225);
DISPLAY INVISIBLE (-4375 4225);
FORCEADD OFFPAGE..1
(-4375 4125);
FORCEPROP 2 LAST $XR0 149 
J 0
(-4627 4125);
DISPLAY 0.638298 (-4627 4125);
PAINT MONO (-4627 4125);
FORCEPROP 2 LAST PATH I44
J 0
(-4575 4175);
DISPLAY 1.021277 (-4575 4175);
DISPLAY INVISIBLE (-4575 4175);
FORCEPROP 1 LAST COMMENT_BODY TRUE
J 0
(-4250 4025);
DISPLAY 0.872340 (-4250 4025);
PAINT GREEN (-4250 4025);
DISPLAY INVISIBLE (-4250 4025);
FORCEPROP 1 LAST OFFPAGE TRUE
J 0
(-4050 4000);
DISPLAY 0.872340 (-4050 4000);
PAINT GREEN (-4050 4000);
DISPLAY INVISIBLE (-4050 4000);
FORCEPROP 2 LAST CDS_LIB standard
J 0
(-4375 4125);
PAINT MONO (-4375 4125);
DISPLAY INVISIBLE (-4375 4125);
FORCEADD OFFPAGE..1
(-4375 4175);
FORCEPROP 2 LAST $XR0 149 
J 0
(-4627 4175);
DISPLAY 0.638298 (-4627 4175);
PAINT MONO (-4627 4175);
FORCEPROP 2 LAST PATH I45
J 0
(-4575 4225);
DISPLAY 1.021277 (-4575 4225);
DISPLAY INVISIBLE (-4575 4225);
FORCEPROP 1 LAST COMMENT_BODY TRUE
J 0
(-4250 4075);
DISPLAY 0.872340 (-4250 4075);
PAINT GREEN (-4250 4075);
DISPLAY INVISIBLE (-4250 4075);
FORCEPROP 1 LAST OFFPAGE TRUE
J 0
(-4050 4050);
DISPLAY 0.872340 (-4050 4050);
PAINT GREEN (-4050 4050);
DISPLAY INVISIBLE (-4050 4050);
FORCEPROP 2 LAST CDS_LIB standard
J 0
(-4375 4175);
PAINT MONO (-4375 4175);
DISPLAY INVISIBLE (-4375 4175);
FORCEADD OFFPAGE..1
(-4375 4075);
FORCEPROP 2 LAST $XR0 149 
J 0
(-4627 4075);
DISPLAY 0.638298 (-4627 4075);
PAINT MONO (-4627 4075);
FORCEPROP 2 LAST PATH I46
J 0
(-4575 4125);
DISPLAY 1.021277 (-4575 4125);
DISPLAY INVISIBLE (-4575 4125);
FORCEPROP 1 LAST COMMENT_BODY TRUE
J 0
(-4250 3975);
DISPLAY 0.872340 (-4250 3975);
PAINT GREEN (-4250 3975);
DISPLAY INVISIBLE (-4250 3975);
FORCEPROP 1 LAST OFFPAGE TRUE
J 0
(-4050 3950);
DISPLAY 0.872340 (-4050 3950);
PAINT GREEN (-4050 3950);
DISPLAY INVISIBLE (-4050 3950);
FORCEPROP 2 LAST CDS_LIB standard
J 0
(-4375 4075);
PAINT MONO (-4375 4075);
DISPLAY INVISIBLE (-4375 4075);
FORCEADD OFFPAGE..2
(-525 4075);
FORCEPROP 2 LAST $XR0 150 
J 0
(-336 4075);
DISPLAY 0.638298 (-336 4075);
PAINT MONO (-336 4075);
FORCEPROP 2 LAST PATH I5
J 0
(-325 4125);
DISPLAY 1.021277 (-325 4125);
DISPLAY INVISIBLE (-325 4125);
FORCEPROP 1 LAST COMMENT_BODY TRUE
J 0
(-570 3980);
DISPLAY 0.872340 (-570 3980);
PAINT GREEN (-570 3980);
DISPLAY INVISIBLE (-570 3980);
FORCEPROP 1 LAST OFFPAGE TRUE
J 0
(-200 3950);
DISPLAY 0.872340 (-200 3950);
PAINT GREEN (-200 3950);
DISPLAY INVISIBLE (-200 3950);
FORCEPROP 2 LAST CDS_LIB standard
J 0
(-525 4075);
PAINT MONO (-525 4075);
DISPLAY INVISIBLE (-525 4075);
FORCEADD OFFPAGE..2
(-5100 4075);
FORCEPROP 2 LAST $XR0 150 
J 0
(-4911 4075);
DISPLAY 0.638298 (-4911 4075);
PAINT MONO (-4911 4075);
FORCEPROP 2 LAST PATH I51
J 0
(-4900 4125);
DISPLAY 1.021277 (-4900 4125);
DISPLAY INVISIBLE (-4900 4125);
FORCEPROP 1 LAST COMMENT_BODY TRUE
J 0
(-5145 3980);
DISPLAY 0.872340 (-5145 3980);
PAINT GREEN (-5145 3980);
DISPLAY INVISIBLE (-5145 3980);
FORCEPROP 1 LAST OFFPAGE TRUE
J 0
(-4775 3950);
DISPLAY 0.872340 (-4775 3950);
PAINT GREEN (-4775 3950);
DISPLAY INVISIBLE (-4775 3950);
FORCEPROP 2 LAST CDS_LIB standard
J 0
(-5100 4075);
PAINT MONO (-5100 4075);
DISPLAY INVISIBLE (-5100 4075);
FORCEADD Q_RES..1
(-5725 4075);
FORCEPROP 1 LAST LOCATION R1625
J 0
(-5950 4075);
DISPLAY 0.489362 (-5950 4075);
PAINT SKYBLUE (-5950 4075);
FORCEPROP 0 LAST $SEC 1
J 0
(-5575 4125);
PAINT MONO (-5575 4125);
DISPLAY INVISIBLE (-5575 4125);
FORCEPROP 0 LAST CDS_SEC 1
J 0
(-5575 4125);
PAINT MONO (-5575 4125);
DISPLAY INVISIBLE (-5575 4125);
FORCEPROP 1 LASTPIN (-5825 4075) $PN 1
J 0
(-5813 4087);
DISPLAY 0.489362 (-5813 4087);
PAINT GREEN (-5813 4087);
FORCEPROP 1 LASTPIN (-5625 4075) $PN 2
J 0
(-5663 4087);
DISPLAY 0.489362 (-5663 4087);
PAINT GREEN (-5663 4087);
FORCEPROP 1 LAST VALUE 0
J 2
(-5575 4075);
DISPLAY 0.489362 (-5575 4075);
PAINT SKYBLUE (-5575 4075);
FORCEPROP 2 LAST CDS_LIB pure_quanta
J 0
(-5725 4075);
PAINT MONO (-5725 4075);
DISPLAY INVISIBLE (-5725 4075);
FORCEPROP 1 LAST PATH I53
J 0
(-5775 4225);
DISPLAY 0.978723 (-5775 4225);
PAINT WHITE (-5775 4225);
DISPLAY INVISIBLE (-5775 4225);
FORCEPROP 1 LAST WATTAGE 1/16W
J 2
(-5750 3925);
DISPLAY 0.978723 (-5750 3925);
PAINT SKYBLUE (-5750 3925);
DISPLAY INVISIBLE (-5750 3925);
FORCEPROP 1 LAST MATERIAL CHIP
J 0
(-5500 4075);
DISPLAY 0.617021 (-5500 4075);
PAINT SKYBLUE (-5500 4075);
DISPLAY INVISIBLE (-5500 4075);
FORCEPROP 1 LAST TOLERANCE 5%
J 0
(-5725 3975);
DISPLAY 0.978723 (-5725 3975);
PAINT SKYBLUE (-5725 3975);
DISPLAY INVISIBLE (-5725 3975);
FORCEPROP 1 LAST PART_NUMBER CS00002JB38
J 0
(-5775 4175);
DISPLAY 0.978723 (-5775 4175);
PAINT SKYBLUE (-5775 4175);
DISPLAY INVISIBLE (-5775 4175);
FORCEPROP 1 LAST PACK_TYPE 0402LF
J 0
(-5475 3925);
DISPLAY 0.978723 (-5475 3925);
PAINT SKYBLUE (-5475 3925);
DISPLAY INVISIBLE (-5475 3925);
FORCEADD UNIVERSAL_POWER..1
(-6475 4900);
FORCEPROP 3 LASTPIN (-6475 4850) SIG_NAME PVDD18_S5_P0\g
J 0
(-6465 4860);
DISPLAY 0.659574 (-6465 4860);
PAINT MONO (-6465 4860);
DISPLAY INVISIBLE (-6465 4860);
FORCEPROP 1 LAST HDL_POWER PVDD18_S5_P0
J 1
(-6450 4950);
DISPLAY 0.489362 (-6450 4950);
PAINT GREEN (-6450 4950);
FORCEPROP 2 LAST CDS_LIB pure_quanta_power
J 0
(-6475 4900);
PAINT MONO (-6475 4900);
DISPLAY INVISIBLE (-6475 4900);
FORCEPROP 1 LAST PATH I54
J 0
(-6425 4925);
DISPLAY 0.872340 (-6425 4925);
PAINT AQUA (-6425 4925);
DISPLAY INVISIBLE (-6425 4925);
FORCEADD GND..1
(-6350 4400);
FORCEPROP 3 LASTPIN (-6350 4450) SIG_NAME GND\g
J 0
(-6340 4460);
DISPLAY 0.659574 (-6340 4460);
PAINT MONO (-6340 4460);
DISPLAY INVISIBLE (-6340 4460);
FORCEPROP 1 LAST SIZE 1B
J 0
(-6275 4350);
DISPLAY 0.872340 (-6275 4350);
PAINT GREEN (-6275 4350);
DISPLAY INVISIBLE (-6275 4350);
FORCEPROP 2 LAST CDS_LIB pure_quanta_power
J 0
(-6350 4400);
DISPLAY INVISIBLE (-6350 4400);
FORCEPROP 1 LAST PATH I55
J 0
(-6275 4400);
DISPLAY 0.872340 (-6275 4400);
PAINT AQUA (-6275 4400);
DISPLAY INVISIBLE (-6275 4400);
FORCEPROP 1 LAST HDL_POWER GND
J 0
(-6350 4550);
DISPLAY 0.872340 (-6350 4550);
PAINT GREEN (-6350 4550);
DISPLAY INVISIBLE (-6350 4550);
FORCEADD Q_CAP..1
(-6350 4625);
FORCEPROP 1 LAST LOCATION C1504
J 0
(-6250 4775);
DISPLAY 0.489362 (-6250 4775);
PAINT SKYBLUE (-6250 4775);
FORCEPROP 2 LAST $SEC 1
J 0
(-6300 4825);
PAINT MONO (-6300 4825);
DISPLAY INVISIBLE (-6300 4825);
FORCEPROP 2 LAST CDS_SEC 1
J 0
(-6300 4825);
PAINT MONO (-6300 4825);
DISPLAY INVISIBLE (-6300 4825);
FORCEPROP 1 LASTPIN (-6350 4725) $PN 1
J 0
(-6340 4705);
DISPLAY 0.489362 (-6340 4705);
PAINT GREEN (-6340 4705);
FORCEPROP 1 LASTPIN (-6350 4525) $PN 2
J 0
(-6340 4505);
DISPLAY 0.489362 (-6340 4505);
PAINT GREEN (-6340 4505);
FORCEPROP 1 LAST MATERIAL X7R
J 0
(-6250 4575);
DISPLAY 0.489362 (-6250 4575);
PAINT SKYBLUE (-6250 4575);
FORCEPROP 1 LAST TOLERANCE 10%
J 0
(-6250 4625);
DISPLAY 0.489362 (-6250 4625);
PAINT SKYBLUE (-6250 4625);
FORCEPROP 1 LAST VALUE 0.1UF
J 0
(-6250 4725);
DISPLAY 0.489362 (-6250 4725);
PAINT SKYBLUE (-6250 4725);
FORCEPROP 1 LAST PART_NUMBER CH4103K1B08
J 0
(-6250 4525);
DISPLAY 0.489362 (-6250 4525);
PAINT SKYBLUE (-6250 4525);
FORCEPROP 1 LAST VOLTAGE 16V
J 0
(-6250 4675);
DISPLAY 0.489362 (-6250 4675);
PAINT SKYBLUE (-6250 4675);
FORCEPROP 1 LAST PACK_TYPE C0402
J 0
(-6250 4475);
DISPLAY 0.489362 (-6250 4475);
PAINT SKYBLUE (-6250 4475);
FORCEPROP 2 LAST CDS_LIB pure_quanta
J 0
(-6350 4625);
DISPLAY INVISIBLE (-6350 4625);
FORCEPROP 1 LAST PATH I56
J 0
(-6300 4775);
DISPLAY 0.978723 (-6300 4775);
PAINT WHITE (-6300 4775);
DISPLAY INVISIBLE (-6300 4775);
FORCEADD OFFPAGE..2
(-525 4125);
FORCEPROP 2 LAST $XR0 150 
J 0
(-336 4125);
DISPLAY 0.638298 (-336 4125);
PAINT MONO (-336 4125);
FORCEPROP 2 LAST PATH I6
J 0
(-325 4175);
DISPLAY 1.021277 (-325 4175);
DISPLAY INVISIBLE (-325 4175);
FORCEPROP 1 LAST COMMENT_BODY TRUE
J 0
(-570 4030);
DISPLAY 0.872340 (-570 4030);
PAINT GREEN (-570 4030);
DISPLAY INVISIBLE (-570 4030);
FORCEPROP 1 LAST OFFPAGE TRUE
J 0
(-200 4000);
DISPLAY 0.872340 (-200 4000);
PAINT GREEN (-200 4000);
DISPLAY INVISIBLE (-200 4000);
FORCEPROP 2 LAST CDS_LIB standard
J 0
(-525 4125);
PAINT MONO (-525 4125);
DISPLAY INVISIBLE (-525 4125);
FORCEADD Q_CAP..1
(-3975 2400);
FORCEPROP 1 LAST LOCATION C1506
J 0
(-4125 2525);
DISPLAY 0.489362 (-4125 2525);
PAINT SKYBLUE (-4125 2525);
FORCEPROP 2 LAST $SEC 1
J 0
(-3925 2600);
PAINT MONO (-3925 2600);
DISPLAY INVISIBLE (-3925 2600);
FORCEPROP 2 LAST CDS_SEC 1
J 0
(-3925 2600);
PAINT MONO (-3925 2600);
DISPLAY INVISIBLE (-3925 2600);
FORCEPROP 1 LASTPIN (-3975 2500) $PN 1
J 0
(-3965 2480);
DISPLAY 0.489362 (-3965 2480);
PAINT GREEN (-3965 2480);
FORCEPROP 1 LASTPIN (-3975 2300) $PN 2
J 0
(-3965 2280);
DISPLAY 0.489362 (-3965 2280);
PAINT GREEN (-3965 2280);
FORCEPROP 1 LAST MATERIAL X7R
J 0
(-4100 2325);
DISPLAY 0.489362 (-4100 2325);
PAINT SKYBLUE (-4100 2325);
FORCEPROP 1 LAST TOLERANCE 10%
J 0
(-4100 2375);
DISPLAY 0.489362 (-4100 2375);
PAINT SKYBLUE (-4100 2375);
FORCEPROP 1 LAST VALUE 0.1UF
J 0
(-4150 2475);
DISPLAY 0.489362 (-4150 2475);
PAINT SKYBLUE (-4150 2475);
FORCEPROP 1 LAST PART_NUMBER CH4103K1B08
J 0
(-4325 2275);
DISPLAY 0.489362 (-4325 2275);
PAINT SKYBLUE (-4325 2275);
FORCEPROP 1 LAST VOLTAGE 16V
J 0
(-4100 2425);
DISPLAY 0.489362 (-4100 2425);
PAINT SKYBLUE (-4100 2425);
FORCEPROP 1 LAST PACK_TYPE C0402
J 0
(-4150 2225);
DISPLAY 0.489362 (-4150 2225);
PAINT SKYBLUE (-4150 2225);
FORCEPROP 2 LAST CDS_LIB pure_quanta
J 0
(-3975 2400);
DISPLAY INVISIBLE (-3975 2400);
FORCEPROP 1 LAST PATH I62
J 0
(-3925 2550);
DISPLAY 0.978723 (-3925 2550);
PAINT WHITE (-3925 2550);
DISPLAY INVISIBLE (-3925 2550);
FORCEADD GND..1
(-3975 2225);
FORCEPROP 3 LASTPIN (-3975 2275) SIG_NAME GND\g
J 0
(-3965 2285);
DISPLAY 0.659574 (-3965 2285);
PAINT MONO (-3965 2285);
DISPLAY INVISIBLE (-3965 2285);
FORCEPROP 1 LAST SIZE 1B
J 0
(-3900 2175);
DISPLAY 0.872340 (-3900 2175);
PAINT GREEN (-3900 2175);
DISPLAY INVISIBLE (-3900 2175);
FORCEPROP 2 LAST CDS_LIB pure_quanta_power
J 0
(-3975 2225);
DISPLAY INVISIBLE (-3975 2225);
FORCEPROP 1 LAST PATH I63
J 0
(-3900 2225);
DISPLAY 0.872340 (-3900 2225);
PAINT AQUA (-3900 2225);
DISPLAY INVISIBLE (-3900 2225);
FORCEPROP 1 LAST HDL_POWER GND
J 0
(-3975 2375);
DISPLAY 0.872340 (-3975 2375);
PAINT GREEN (-3975 2375);
DISPLAY INVISIBLE (-3975 2375);
FORCEADD OFFPAGE..1
(-4375 2075);
FORCEPROP 2 LAST $XR0 148 
J 0
(-4627 2075);
DISPLAY 0.638298 (-4627 2075);
PAINT MONO (-4627 2075);
FORCEPROP 2 LAST PATH I64
J 0
(-4575 2125);
DISPLAY 1.021277 (-4575 2125);
DISPLAY INVISIBLE (-4575 2125);
FORCEPROP 1 LAST COMMENT_BODY TRUE
J 0
(-4250 1975);
DISPLAY 0.872340 (-4250 1975);
PAINT GREEN (-4250 1975);
DISPLAY INVISIBLE (-4250 1975);
FORCEPROP 1 LAST OFFPAGE TRUE
J 0
(-4050 1950);
DISPLAY 0.872340 (-4050 1950);
PAINT GREEN (-4050 1950);
DISPLAY INVISIBLE (-4050 1950);
FORCEPROP 2 LAST CDS_LIB standard
J 0
(-4375 2075);
PAINT MONO (-4375 2075);
DISPLAY INVISIBLE (-4375 2075);
FORCEADD OFFPAGE..1
(-4375 2025);
FORCEPROP 2 LAST $XR0 148 
J 0
(-4627 2025);
DISPLAY 0.638298 (-4627 2025);
PAINT MONO (-4627 2025);
FORCEPROP 2 LAST PATH I65
J 0
(-4575 2075);
DISPLAY 1.021277 (-4575 2075);
DISPLAY INVISIBLE (-4575 2075);
FORCEPROP 1 LAST COMMENT_BODY TRUE
J 0
(-4250 1925);
DISPLAY 0.872340 (-4250 1925);
PAINT GREEN (-4250 1925);
DISPLAY INVISIBLE (-4250 1925);
FORCEPROP 1 LAST OFFPAGE TRUE
J 0
(-4050 1900);
DISPLAY 0.872340 (-4050 1900);
PAINT GREEN (-4050 1900);
DISPLAY INVISIBLE (-4050 1900);
FORCEPROP 2 LAST CDS_LIB standard
J 0
(-4375 2025);
PAINT MONO (-4375 2025);
DISPLAY INVISIBLE (-4375 2025);
FORCEADD Q_CAP..1
(-5375 3725);
FORCEPROP 1 LAST LOCATION C86
J 0
(-5300 3825);
DISPLAY 0.489362 (-5300 3825);
PAINT SKYBLUE (-5300 3825);
FORCEPROP 0 LAST $SEC 1
J 0
(-5300 3875);
PAINT MONO (-5300 3875);
DISPLAY INVISIBLE (-5300 3875);
FORCEPROP 0 LAST CDS_SEC 1
J 0
(-5300 3875);
PAINT MONO (-5300 3875);
DISPLAY INVISIBLE (-5300 3875);
FORCEPROP 1 LASTPIN (-5375 3825) $PN 1
J 0
(-5365 3805);
DISPLAY 0.489362 (-5365 3805);
PAINT GREEN (-5365 3805);
FORCEPROP 1 LASTPIN (-5375 3625) $PN 2
J 0
(-5365 3605);
DISPLAY 0.489362 (-5365 3605);
PAINT GREEN (-5365 3605);
FORCEPROP 1 LAST MATERIAL EMPTY
J 0
(-5300 3625);
DISPLAY 0.489362 (-5300 3625);
PAINT RED (-5300 3625);
FORCEPROP 1 LAST TOLERANCE 10%
J 0
(-5300 3675);
DISPLAY 0.489362 (-5300 3675);
PAINT SKYBLUE (-5300 3675);
FORCEPROP 1 LAST VALUE 0.01UF
J 0
(-5300 3775);
DISPLAY 0.489362 (-5300 3775);
PAINT SKYBLUE (-5300 3775);
FORCEPROP 1 LAST VOLTAGE 50V
J 0
(-5300 3725);
DISPLAY 0.489362 (-5300 3725);
PAINT SKYBLUE (-5300 3725);
FORCEPROP 1 LAST PACK_TYPE C0402
J 0
(-5300 3575);
DISPLAY 0.489362 (-5300 3575);
PAINT SKYBLUE (-5300 3575);
FORCEPROP 2 LAST CDS_LIB pure_quanta
J 0
(-5375 3725);
PAINT MONO (-5375 3725);
DISPLAY INVISIBLE (-5375 3725);
FORCEPROP 1 LAST PATH I66
J 0
(-5325 3875);
DISPLAY 0.978723 (-5325 3875);
PAINT WHITE (-5325 3875);
DISPLAY INVISIBLE (-5325 3875);
FORCEPROP 1 LAST PART_NUMBER CH31006KB18
R 1
J 0
(-5425 3475);
DISPLAY 0.617021 (-5425 3475);
PAINT SKYBLUE (-5425 3475);
DISPLAY INVISIBLE (-5425 3475);
FORCEPROP 2 LAST ROOM BMCLESS
J 0
(-5325 3875);
DISPLAY 1.148936 (-5325 3875);
PAINT RED (-5325 3875);
DISPLAY INVISIBLE (-5325 3875);
FORCEADD GND..1
(-5375 3500);
FORCEPROP 3 LASTPIN (-5375 3550) SIG_NAME GND\g
J 0
(-5365 3560);
DISPLAY 0.659574 (-5365 3560);
PAINT MONO (-5365 3560);
DISPLAY INVISIBLE (-5365 3560);
FORCEPROP 1 LAST SIZE 1B
J 0
(-5300 3450);
DISPLAY 0.872340 (-5300 3450);
PAINT GREEN (-5300 3450);
DISPLAY INVISIBLE (-5300 3450);
FORCEPROP 2 LAST CDS_LIB pure_quanta_power
J 0
(-5375 3500);
DISPLAY INVISIBLE (-5375 3500);
FORCEPROP 1 LAST PATH I67
J 0
(-5300 3500);
DISPLAY 0.872340 (-5300 3500);
PAINT AQUA (-5300 3500);
DISPLAY INVISIBLE (-5300 3500);
FORCEPROP 1 LAST HDL_POWER GND
J 0
(-5375 3650);
DISPLAY 0.872340 (-5375 3650);
PAINT GREEN (-5375 3650);
DISPLAY INVISIBLE (-5375 3650);
FORCEADD OFFPAGE..1
R 2
(-5100 3925);
FORCEPROP 2 LAST $XR0 150 
J 0
(-4914 3925);
DISPLAY 0.638298 (-4914 3925);
PAINT MONO (-4914 3925);
FORCEPROP 2 LAST PATH I68
J 0
(-4900 3975);
DISPLAY 1.021277 (-4900 3975);
DISPLAY INVISIBLE (-4900 3975);
FORCEPROP 1 LAST COMMENT_BODY TRUE
J 2
(-5225 3825);
DISPLAY 0.872340 (-5225 3825);
PAINT GREEN (-5225 3825);
DISPLAY INVISIBLE (-5225 3825);
FORCEPROP 1 LAST OFFPAGE TRUE
J 2
(-5425 3800);
DISPLAY 0.872340 (-5425 3800);
PAINT GREEN (-5425 3800);
DISPLAY INVISIBLE (-5425 3800);
FORCEPROP 2 LAST CDS_LIB standard
J 0
(-5100 3925);
PAINT MONO (-5100 3925);
DISPLAY INVISIBLE (-5100 3925);
FORCEADD OFFPAGE..1
(-4375 1975);
FORCEPROP 2 LAST $XR0 79 
J 0
(-4596 1975);
DISPLAY 0.638298 (-4596 1975);
PAINT MONO (-4596 1975);
FORCEPROP 2 LAST PATH I69
J 0
(-4575 2025);
DISPLAY 1.021277 (-4575 2025);
DISPLAY INVISIBLE (-4575 2025);
FORCEPROP 1 LAST COMMENT_BODY TRUE
J 0
(-4250 1875);
DISPLAY 0.872340 (-4250 1875);
PAINT GREEN (-4250 1875);
DISPLAY INVISIBLE (-4250 1875);
FORCEPROP 1 LAST OFFPAGE TRUE
J 0
(-4050 1850);
DISPLAY 0.872340 (-4050 1850);
PAINT GREEN (-4050 1850);
DISPLAY INVISIBLE (-4050 1850);
FORCEPROP 2 LAST CDS_LIB standard
J 0
(-4375 1975);
PAINT MONO (-4375 1975);
DISPLAY INVISIBLE (-4375 1975);
FORCEADD Q_RES..1
(-1675 4225);
FORCEPROP 1 LAST LOCATION R1633
J 0
(-2050 4225);
DISPLAY 0.489362 (-2050 4225);
PAINT SKYBLUE (-2050 4225);
FORCEPROP 0 LAST $SEC 1
J 0
(-1925 4275);
PAINT MONO (-1925 4275);
DISPLAY INVISIBLE (-1925 4275);
FORCEPROP 0 LAST CDS_SEC 1
J 0
(-1925 4275);
PAINT MONO (-1925 4275);
DISPLAY INVISIBLE (-1925 4275);
FORCEPROP 1 LASTPIN (-1775 4225) $PN 1
J 0
(-1763 4237);
DISPLAY 0.489362 (-1763 4237);
PAINT GREEN (-1763 4237);
FORCEPROP 1 LASTPIN (-1575 4225) $PN 2
J 0
(-1613 4237);
DISPLAY 0.489362 (-1613 4237);
PAINT GREEN (-1613 4237);
FORCEPROP 1 LAST TOLERANCE 1%
J 0
(-1575 4200);
DISPLAY 0.489362 (-1575 4200);
PAINT SKYBLUE (-1575 4200);
FORCEPROP 1 LAST VALUE 22
J 2
(-1775 4225);
DISPLAY 0.489362 (-1775 4225);
PAINT SKYBLUE (-1775 4225);
FORCEPROP 2 LAST CDS_LIB pure_quanta
J 0
(-1675 4225);
PAINT MONO (-1675 4225);
DISPLAY INVISIBLE (-1675 4225);
FORCEPROP 1 LAST PATH I7
J 0
(-1725 4375);
DISPLAY 0.978723 (-1725 4375);
PAINT WHITE (-1725 4375);
DISPLAY INVISIBLE (-1725 4375);
FORCEPROP 1 LAST WATTAGE 1/16W
J 2
(-1700 4075);
DISPLAY 0.978723 (-1700 4075);
PAINT SKYBLUE (-1700 4075);
DISPLAY INVISIBLE (-1700 4075);
FORCEPROP 1 LAST MATERIAL CHIP
J 0
(-1850 4200);
DISPLAY 0.489362 (-1850 4200);
PAINT SKYBLUE (-1850 4200);
DISPLAY INVISIBLE (-1850 4200);
FORCEPROP 1 LAST PART_NUMBER CS02202FB12
J 0
(-1725 4325);
DISPLAY 0.978723 (-1725 4325);
PAINT SKYBLUE (-1725 4325);
DISPLAY INVISIBLE (-1725 4325);
FORCEPROP 1 LAST PACK_TYPE 0402LF
J 0
(-1425 4075);
DISPLAY 0.978723 (-1425 4075);
PAINT SKYBLUE (-1425 4075);
DISPLAY INVISIBLE (-1425 4075);
FORCEADD OFFPAGE..1
(-4375 1925);
FORCEPROP 2 LAST $XR0 117 
J 0
(-4627 1925);
DISPLAY 0.638298 (-4627 1925);
PAINT MONO (-4627 1925);
FORCEPROP 2 LAST PATH I70
J 0
(-4575 1975);
DISPLAY 1.021277 (-4575 1975);
DISPLAY INVISIBLE (-4575 1975);
FORCEPROP 1 LAST COMMENT_BODY TRUE
J 0
(-4250 1825);
DISPLAY 0.872340 (-4250 1825);
PAINT GREEN (-4250 1825);
DISPLAY INVISIBLE (-4250 1825);
FORCEPROP 1 LAST OFFPAGE TRUE
J 0
(-4050 1800);
DISPLAY 0.872340 (-4050 1800);
PAINT GREEN (-4050 1800);
DISPLAY INVISIBLE (-4050 1800);
FORCEPROP 2 LAST CDS_LIB standard
J 0
(-4375 1925);
PAINT MONO (-4375 1925);
DISPLAY INVISIBLE (-4375 1925);
FORCEADD UNIVERSAL_POWER..1
(-6425 3725);
FORCEPROP 3 LASTPIN (-6425 3675) SIG_NAME PVDD18_S5_P0\g
J 0
(-6415 3685);
DISPLAY 0.659574 (-6415 3685);
PAINT MONO (-6415 3685);
DISPLAY INVISIBLE (-6415 3685);
FORCEPROP 1 LAST HDL_POWER PVDD18_S5_P0
J 1
(-6400 3775);
DISPLAY 0.489362 (-6400 3775);
PAINT GREEN (-6400 3775);
FORCEPROP 2 LAST CDS_LIB pure_quanta_power
J 0
(-6425 3725);
DISPLAY INVISIBLE (-6425 3725);
FORCEPROP 1 LAST PATH I71
J 0
(-6375 3750);
DISPLAY 0.872340 (-6375 3750);
PAINT AQUA (-6375 3750);
DISPLAY INVISIBLE (-6375 3750);
FORCEADD UNIVERSAL_POWER..1
(-6450 3000);
FORCEPROP 3 LASTPIN (-6450 2950) SIG_NAME PVDD18_S5_P0\g
J 0
(-6440 2960);
DISPLAY 0.659574 (-6440 2960);
PAINT MONO (-6440 2960);
DISPLAY INVISIBLE (-6440 2960);
FORCEPROP 1 LAST HDL_POWER PVDD18_S5_P0
J 1
(-6425 3050);
DISPLAY 0.489362 (-6425 3050);
PAINT GREEN (-6425 3050);
FORCEPROP 2 LAST CDS_LIB pure_quanta_power
J 0
(-6450 3000);
PAINT MONO (-6450 3000);
DISPLAY INVISIBLE (-6450 3000);
FORCEPROP 1 LAST PATH I73
J 0
(-6400 3025);
DISPLAY 0.872340 (-6400 3025);
PAINT AQUA (-6400 3025);
DISPLAY INVISIBLE (-6400 3025);
FORCEADD Q_CAP..1
(-6325 2725);
FORCEPROP 1 LAST LOCATION C1505
J 0
(-6250 2850);
DISPLAY 0.489362 (-6250 2850);
PAINT SKYBLUE (-6250 2850);
FORCEPROP 2 LAST $SEC 1
J 0
(-6275 2925);
PAINT MONO (-6275 2925);
DISPLAY INVISIBLE (-6275 2925);
FORCEPROP 2 LAST CDS_SEC 1
J 0
(-6275 2925);
PAINT MONO (-6275 2925);
DISPLAY INVISIBLE (-6275 2925);
FORCEPROP 1 LASTPIN (-6325 2825) $PN 1
J 0
(-6315 2805);
DISPLAY 0.489362 (-6315 2805);
PAINT GREEN (-6315 2805);
FORCEPROP 1 LASTPIN (-6325 2625) $PN 2
J 0
(-6315 2605);
DISPLAY 0.489362 (-6315 2605);
PAINT GREEN (-6315 2605);
FORCEPROP 1 LAST MATERIAL X7R
J 0
(-6250 2650);
DISPLAY 0.489362 (-6250 2650);
PAINT SKYBLUE (-6250 2650);
FORCEPROP 1 LAST TOLERANCE 10%
J 0
(-6250 2700);
DISPLAY 0.489362 (-6250 2700);
PAINT SKYBLUE (-6250 2700);
FORCEPROP 1 LAST VALUE 0.1UF
J 0
(-6250 2800);
DISPLAY 0.489362 (-6250 2800);
PAINT SKYBLUE (-6250 2800);
FORCEPROP 1 LAST PART_NUMBER CH4103K1B08
J 0
(-6250 2600);
DISPLAY 0.489362 (-6250 2600);
PAINT SKYBLUE (-6250 2600);
FORCEPROP 1 LAST VOLTAGE 16V
J 0
(-6250 2750);
DISPLAY 0.489362 (-6250 2750);
PAINT SKYBLUE (-6250 2750);
FORCEPROP 1 LAST PACK_TYPE C0402
J 0
(-6250 2550);
DISPLAY 0.489362 (-6250 2550);
PAINT SKYBLUE (-6250 2550);
FORCEPROP 2 LAST CDS_LIB pure_quanta
J 0
(-6325 2725);
DISPLAY INVISIBLE (-6325 2725);
FORCEPROP 1 LAST PATH I74
J 0
(-6275 2875);
DISPLAY 0.978723 (-6275 2875);
PAINT WHITE (-6275 2875);
DISPLAY INVISIBLE (-6275 2875);
FORCEADD GND..1
(-6325 2500);
FORCEPROP 3 LASTPIN (-6325 2550) SIG_NAME GND\g
J 0
(-6315 2560);
DISPLAY 0.659574 (-6315 2560);
PAINT MONO (-6315 2560);
DISPLAY INVISIBLE (-6315 2560);
FORCEPROP 1 LAST SIZE 1B
J 0
(-6250 2450);
DISPLAY 0.872340 (-6250 2450);
PAINT GREEN (-6250 2450);
DISPLAY INVISIBLE (-6250 2450);
FORCEPROP 2 LAST CDS_LIB pure_quanta_power
J 0
(-6325 2500);
DISPLAY INVISIBLE (-6325 2500);
FORCEPROP 1 LAST PATH I75
J 0
(-6250 2500);
DISPLAY 0.872340 (-6250 2500);
PAINT AQUA (-6250 2500);
DISPLAY INVISIBLE (-6250 2500);
FORCEPROP 1 LAST HDL_POWER GND
J 0
(-6325 2650);
DISPLAY 0.872340 (-6325 2650);
PAINT GREEN (-6325 2650);
DISPLAY INVISIBLE (-6325 2650);
FORCEADD SN74AVC2T245RSWR..1
R 2
(-7025 4000);
FORCEPROP 1 LAST LOCATION U146
J 2
(-6775 4500);
DISPLAY 0.489362 (-6775 4500);
PAINT SKYBLUE (-6775 4500);
FORCEPROP 0 LAST $SEC 1
J 0
(-6800 4675);
PAINT MONO (-6800 4675);
DISPLAY INVISIBLE (-6800 4675);
FORCEPROP 0 LAST CDS_SEC 1
J 0
(-6800 4675);
PAINT MONO (-6800 4675);
DISPLAY INVISIBLE (-6800 4675);
FORCEPROP 0 LASTPIN (-7425 4125) $PN 8
J 2
(-7435 4135);
DISPLAY 0.489362 (-7435 4135);
PAINT MONO (-7435 4135);
FORCEPROP 0 LASTPIN (-7425 3975) $PN 9
J 2
(-7435 3985);
DISPLAY 0.489362 (-7435 3985);
PAINT MONO (-7435 3985);
FORCEPROP 0 LASTPIN (-6625 4075) $PN 5
J 0
(-6615 4085);
DISPLAY 0.489362 (-6615 4085);
PAINT MONO (-6615 4085);
FORCEPROP 0 LASTPIN (-6625 3925) $PN 4
J 0
(-6615 3935);
DISPLAY 0.489362 (-6615 3935);
PAINT MONO (-6615 3935);
FORCEPROP 0 LASTPIN (-7425 4075) $PN 10
J 2
(-7435 4085);
DISPLAY 0.489362 (-7435 4085);
PAINT MONO (-7435 4085);
FORCEPROP 0 LASTPIN (-7425 3925) $PN 1
J 2
(-7435 3935);
DISPLAY 0.489362 (-7435 3935);
PAINT MONO (-7435 3935);
FORCEPROP 0 LASTPIN (-7425 3675) $PN 3
J 2
(-7435 3685);
DISPLAY 0.489362 (-7435 3685);
PAINT MONO (-7435 3685);
FORCEPROP 0 LASTPIN (-7425 3825) $PN 2
J 2
(-7435 3835);
DISPLAY 0.489362 (-7435 3835);
PAINT MONO (-7435 3835);
FORCEPROP 0 LASTPIN (-6625 4325) $PN 7
J 0
(-6615 4335);
DISPLAY 0.489362 (-6615 4335);
PAINT MONO (-6615 4335);
FORCEPROP 0 LASTPIN (-6625 4275) $PN 6
J 0
(-6615 4285);
DISPLAY 0.489362 (-6615 4285);
PAINT MONO (-6615 4285);
FORCEPROP 2 LAST PART_TYPE SMLF
J 2
(-6775 4600);
PAINT MONO (-6775 4600);
FORCEPROP 1 LAST MATERIAL IC
J 2
(-6780 4382);
DISPLAY 0.489362 (-6780 4382);
PAINT SKYBLUE (-6780 4382);
FORCEPROP 2 LAST VALUE SN74AVC2T245RSWR
J 2
(-6775 4550);
DISPLAY 0.489362 (-6775 4550);
PAINT SKYBLUE (-6775 4550);
FORCEPROP 1 LAST PART_NUMBER AL02T245000
J 2
(-6780 4451);
DISPLAY 0.489362 (-6780 4451);
PAINT SKYBLUE (-6780 4451);
FORCEPROP 1 LAST CDS_LMAN_SYM_OUTLINE -250,375,250,-375
J 2
(-7025 4000);
DISPLAY 0.468085 (-7025 4000);
PAINT GREEN (-7025 4000);
DISPLAY INVISIBLE (-7025 4000);
FORCEPROP 2 LAST CDS_LIB pure_quanta
J 2
(-7025 4000);
PAINT MONO (-7025 4000);
DISPLAY INVISIBLE (-7025 4000);
FORCEPROP 1 LAST NEEDS_NO_SIZE TRUE
J 2
(-7275 3682);
DISPLAY 0.723404 (-7275 3682);
PAINT GREEN (-7275 3682);
DISPLAY INVISIBLE (-7275 3682);
FORCEPROP 1 LAST PATH I76
J 2
(-7275 3625);
DISPLAY 0.723404 (-7275 3625);
PAINT GREEN (-7275 3625);
DISPLAY INVISIBLE (-7275 3625);
FORCEADD GND..1
(-7650 3575);
FORCEPROP 3 LASTPIN (-7650 3625) SIG_NAME GND\g
J 0
(-7640 3635);
DISPLAY 0.659574 (-7640 3635);
PAINT MONO (-7640 3635);
DISPLAY INVISIBLE (-7640 3635);
FORCEPROP 1 LAST SIZE 1B
J 0
(-7575 3525);
DISPLAY 0.872340 (-7575 3525);
PAINT GREEN (-7575 3525);
DISPLAY INVISIBLE (-7575 3525);
FORCEPROP 2 LAST CDS_LIB pure_quanta_power
J 0
(-7650 3575);
PAINT MONO (-7650 3575);
DISPLAY INVISIBLE (-7650 3575);
FORCEPROP 1 LAST PATH I77
J 0
(-7575 3575);
DISPLAY 0.872340 (-7575 3575);
PAINT AQUA (-7575 3575);
DISPLAY INVISIBLE (-7575 3575);
FORCEPROP 1 LAST HDL_POWER GND
J 0
(-7650 3725);
DISPLAY 0.872340 (-7650 3725);
PAINT GREEN (-7650 3725);
DISPLAY INVISIBLE (-7650 3725);
FORCEADD UNIVERSAL_POWER..1
(-7700 3125);
FORCEPROP 3 LASTPIN (-7700 3075) SIG_NAME P3V3_STBY\g
J 0
(-7690 3085);
DISPLAY 0.659574 (-7690 3085);
PAINT MONO (-7690 3085);
DISPLAY INVISIBLE (-7690 3085);
FORCEPROP 1 LAST HDL_POWER P3V3_STBY
J 1
(-7700 3175);
DISPLAY 0.489362 (-7700 3175);
PAINT GREEN (-7700 3175);
FORCEPROP 2 LAST CDS_LIB pure_quanta_power
J 0
(-7700 3125);
PAINT MONO (-7700 3125);
DISPLAY INVISIBLE (-7700 3125);
FORCEPROP 1 LAST PATH I78
J 0
(-7650 3150);
DISPLAY 0.872340 (-7650 3150);
PAINT AQUA (-7650 3150);
DISPLAY INVISIBLE (-7650 3150);
FORCEADD Q_RES..1
(-1675 4125);
FORCEPROP 1 LAST LOCATION R1635
J 0
(-2050 4125);
DISPLAY 0.489362 (-2050 4125);
PAINT SKYBLUE (-2050 4125);
FORCEPROP 0 LAST $SEC 1
J 0
(-1925 4175);
PAINT MONO (-1925 4175);
DISPLAY INVISIBLE (-1925 4175);
FORCEPROP 0 LAST CDS_SEC 1
J 0
(-1925 4175);
PAINT MONO (-1925 4175);
DISPLAY INVISIBLE (-1925 4175);
FORCEPROP 1 LASTPIN (-1775 4125) $PN 1
J 0
(-1763 4137);
DISPLAY 0.489362 (-1763 4137);
PAINT GREEN (-1763 4137);
FORCEPROP 1 LASTPIN (-1575 4125) $PN 2
J 0
(-1613 4137);
DISPLAY 0.489362 (-1613 4137);
PAINT GREEN (-1613 4137);
FORCEPROP 1 LAST TOLERANCE 1%
J 0
(-1575 4100);
DISPLAY 0.489362 (-1575 4100);
PAINT SKYBLUE (-1575 4100);
FORCEPROP 1 LAST VALUE 22
J 2
(-1775 4125);
DISPLAY 0.489362 (-1775 4125);
PAINT SKYBLUE (-1775 4125);
FORCEPROP 2 LAST CDS_LIB pure_quanta
J 0
(-1675 4125);
PAINT MONO (-1675 4125);
DISPLAY INVISIBLE (-1675 4125);
FORCEPROP 1 LAST PATH I8
J 0
(-1725 4275);
DISPLAY 0.978723 (-1725 4275);
PAINT WHITE (-1725 4275);
DISPLAY INVISIBLE (-1725 4275);
FORCEPROP 1 LAST WATTAGE 1/16W
J 2
(-1700 3975);
DISPLAY 0.978723 (-1700 3975);
PAINT SKYBLUE (-1700 3975);
DISPLAY INVISIBLE (-1700 3975);
FORCEPROP 1 LAST MATERIAL CHIP
J 0
(-1850 4100);
DISPLAY 0.489362 (-1850 4100);
PAINT SKYBLUE (-1850 4100);
DISPLAY INVISIBLE (-1850 4100);
FORCEPROP 1 LAST PART_NUMBER CS02202FB12
J 0
(-1725 4225);
DISPLAY 0.978723 (-1725 4225);
PAINT SKYBLUE (-1725 4225);
DISPLAY INVISIBLE (-1725 4225);
FORCEPROP 1 LAST PACK_TYPE 0402LF
J 0
(-1425 3975);
DISPLAY 0.978723 (-1425 3975);
PAINT SKYBLUE (-1425 3975);
DISPLAY INVISIBLE (-1425 3975);
FORCEADD Q_CAP..1
(-7825 2800);
FORCEPROP 1 LAST LOCATION C1503
J 0
(-7975 2925);
DISPLAY 0.489362 (-7975 2925);
PAINT SKYBLUE (-7975 2925);
FORCEPROP 2 LAST $SEC 1
J 0
(-7775 3000);
PAINT MONO (-7775 3000);
DISPLAY INVISIBLE (-7775 3000);
FORCEPROP 2 LAST CDS_SEC 1
J 0
(-7775 3000);
PAINT MONO (-7775 3000);
DISPLAY INVISIBLE (-7775 3000);
FORCEPROP 1 LASTPIN (-7825 2900) $PN 1
J 0
(-7815 2880);
DISPLAY 0.489362 (-7815 2880);
PAINT GREEN (-7815 2880);
FORCEPROP 1 LASTPIN (-7825 2700) $PN 2
J 0
(-7815 2680);
DISPLAY 0.489362 (-7815 2680);
PAINT GREEN (-7815 2680);
FORCEPROP 1 LAST MATERIAL X7R
J 0
(-7950 2725);
DISPLAY 0.489362 (-7950 2725);
PAINT SKYBLUE (-7950 2725);
FORCEPROP 1 LAST TOLERANCE 10%
J 0
(-7950 2775);
DISPLAY 0.489362 (-7950 2775);
PAINT SKYBLUE (-7950 2775);
FORCEPROP 1 LAST VALUE 0.1UF
J 0
(-8000 2875);
DISPLAY 0.489362 (-8000 2875);
PAINT SKYBLUE (-8000 2875);
FORCEPROP 1 LAST PART_NUMBER CH4103K1B08
J 0
(-8175 2675);
DISPLAY 0.489362 (-8175 2675);
PAINT SKYBLUE (-8175 2675);
FORCEPROP 1 LAST VOLTAGE 16V
J 0
(-7950 2825);
DISPLAY 0.489362 (-7950 2825);
PAINT SKYBLUE (-7950 2825);
FORCEPROP 1 LAST PACK_TYPE C0402
J 0
(-8000 2625);
DISPLAY 0.489362 (-8000 2625);
PAINT SKYBLUE (-8000 2625);
FORCEPROP 2 LAST CDS_LIB pure_quanta
J 0
(-7825 2800);
DISPLAY INVISIBLE (-7825 2800);
FORCEPROP 1 LAST PATH I80
J 0
(-7775 2950);
DISPLAY 0.978723 (-7775 2950);
PAINT WHITE (-7775 2950);
DISPLAY INVISIBLE (-7775 2950);
FORCEADD GND..1
(-7825 2625);
FORCEPROP 3 LASTPIN (-7825 2675) SIG_NAME GND\g
J 0
(-7815 2685);
DISPLAY 0.659574 (-7815 2685);
PAINT MONO (-7815 2685);
DISPLAY INVISIBLE (-7815 2685);
FORCEPROP 2 LAST CDS_LIB pure_quanta_power
J 0
(-7825 2625);
DISPLAY INVISIBLE (-7825 2625);
FORCEPROP 1 LAST SIZE 1B
J 0
(-7750 2575);
DISPLAY 0.872340 (-7750 2575);
PAINT GREEN (-7750 2575);
DISPLAY INVISIBLE (-7750 2575);
FORCEPROP 1 LAST PATH I81
J 0
(-7750 2625);
DISPLAY 0.872340 (-7750 2625);
PAINT AQUA (-7750 2625);
DISPLAY INVISIBLE (-7750 2625);
FORCEPROP 1 LAST HDL_POWER GND
J 0
(-7825 2775);
DISPLAY 0.872340 (-7825 2775);
PAINT GREEN (-7825 2775);
DISPLAY INVISIBLE (-7825 2775);
FORCEADD UNIVERSAL_POWER..1
(-7475 1400);
FORCEPROP 3 LASTPIN (-7475 1350) SIG_NAME P3V3_STBY\g
J 0
(-7465 1360);
DISPLAY 0.659574 (-7465 1360);
PAINT MONO (-7465 1360);
DISPLAY INVISIBLE (-7465 1360);
FORCEPROP 1 LAST HDL_POWER P3V3_STBY
J 1
(-7475 1450);
DISPLAY 0.489362 (-7475 1450);
PAINT GREEN (-7475 1450);
FORCEPROP 2 LAST CDS_LIB pure_quanta_power
J 0
(-7475 1400);
DISPLAY INVISIBLE (-7475 1400);
FORCEPROP 1 LAST PATH I82
J 0
(-7425 1425);
DISPLAY 0.872340 (-7425 1425);
PAINT AQUA (-7425 1425);
DISPLAY INVISIBLE (-7425 1425);
FORCEADD Q_RES..2
(-7475 1200);
FORCEPROP 1 LAST LOCATION R1622
J 0
(-7370 1375);
DISPLAY 0.489362 (-7370 1375);
PAINT SKYBLUE (-7370 1375);
FORCEPROP 0 LAST $SEC 1
J 0
(-7350 1425);
PAINT MONO (-7350 1425);
DISPLAY INVISIBLE (-7350 1425);
FORCEPROP 0 LAST CDS_SEC 1
J 0
(-7350 1425);
PAINT MONO (-7350 1425);
DISPLAY INVISIBLE (-7350 1425);
FORCEPROP 1 LASTPIN (-7475 1300) $PN 1
J 0
(-7470 1262);
DISPLAY 0.489362 (-7470 1262);
PAINT GREEN (-7470 1262);
FORCEPROP 1 LASTPIN (-7475 1100) $PN 2
J 0
(-7470 1110);
DISPLAY 0.489362 (-7470 1110);
PAINT GREEN (-7470 1110);
FORCEPROP 1 LAST PACK_TYPE 0402LF
J 0
(-7370 1125);
DISPLAY 0.489362 (-7370 1125);
PAINT SKYBLUE (-7370 1125);
FORCEPROP 1 LAST PART_NUMBER TMP_QCS24702JB38
J 0
(-7370 1075);
DISPLAY 0.489362 (-7370 1075);
PAINT SKYBLUE (-7370 1075);
FORCEPROP 1 LAST VALUE 4.7K
J 0
(-7370 1325);
DISPLAY 0.489362 (-7370 1325);
PAINT SKYBLUE (-7370 1325);
FORCEPROP 1 LAST TOLERANCE 5%
J 0
(-7370 1225);
DISPLAY 0.489362 (-7370 1225);
PAINT SKYBLUE (-7370 1225);
FORCEPROP 1 LAST MATERIAL CHIP
J 0
(-7375 1275);
DISPLAY 0.489362 (-7375 1275);
PAINT SKYBLUE (-7375 1275);
FORCEPROP 1 LAST WATTAGE 1/16W
J 0
(-7370 1175);
DISPLAY 0.489362 (-7370 1175);
PAINT SKYBLUE (-7370 1175);
FORCEPROP 2 LAST CDS_LIB pure_quanta
J 0
(-7475 1200);
PAINT MONO (-7475 1200);
DISPLAY INVISIBLE (-7475 1200);
FORCEPROP 1 LAST PATH I83
J 0
(-7425 1375);
DISPLAY 0.978723 (-7425 1375);
PAINT WHITE (-7425 1375);
DISPLAY INVISIBLE (-7425 1375);
FORCEADD GND..1
(-7750 1675);
FORCEPROP 3 LASTPIN (-7750 1725) SIG_NAME GND\g
J 0
(-7740 1735);
DISPLAY 0.659574 (-7740 1735);
PAINT MONO (-7740 1735);
DISPLAY INVISIBLE (-7740 1735);
FORCEPROP 2 LAST CDS_LIB pure_quanta_power
J 0
(-7750 1675);
PAINT MONO (-7750 1675);
DISPLAY INVISIBLE (-7750 1675);
FORCEPROP 1 LAST SIZE 1B
J 0
(-7675 1625);
DISPLAY 0.872340 (-7675 1625);
PAINT GREEN (-7675 1625);
DISPLAY INVISIBLE (-7675 1625);
FORCEPROP 1 LAST PATH I84
J 0
(-7675 1675);
DISPLAY 0.872340 (-7675 1675);
PAINT AQUA (-7675 1675);
DISPLAY INVISIBLE (-7675 1675);
FORCEPROP 1 LAST HDL_POWER GND
J 0
(-7750 1825);
DISPLAY 0.872340 (-7750 1825);
PAINT GREEN (-7750 1825);
DISPLAY INVISIBLE (-7750 1825);
FORCEADD GND..1
(-7475 300);
FORCEPROP 3 LASTPIN (-7475 350) SIG_NAME GND\g
J 0
(-7465 360);
DISPLAY 0.659574 (-7465 360);
PAINT MONO (-7465 360);
DISPLAY INVISIBLE (-7465 360);
FORCEPROP 2 LAST CDS_LIB pure_quanta_power
J 0
(-7475 300);
PAINT MONO (-7475 300);
DISPLAY INVISIBLE (-7475 300);
FORCEPROP 1 LAST SIZE 1B
J 0
(-7400 250);
DISPLAY 0.872340 (-7400 250);
PAINT GREEN (-7400 250);
DISPLAY INVISIBLE (-7400 250);
FORCEPROP 1 LAST PATH I85
J 0
(-7400 300);
DISPLAY 0.872340 (-7400 300);
PAINT AQUA (-7400 300);
DISPLAY INVISIBLE (-7400 300);
FORCEPROP 1 LAST HDL_POWER GND
J 0
(-7475 450);
DISPLAY 0.872340 (-7475 450);
PAINT GREEN (-7475 450);
DISPLAY INVISIBLE (-7475 450);
FORCEADD Q_RES..1
(-1675 4075);
FORCEPROP 1 LAST LOCATION R1636
J 0
(-2050 4075);
DISPLAY 0.489362 (-2050 4075);
PAINT SKYBLUE (-2050 4075);
FORCEPROP 0 LAST $SEC 1
J 0
(-1925 4125);
PAINT MONO (-1925 4125);
DISPLAY INVISIBLE (-1925 4125);
FORCEPROP 0 LAST CDS_SEC 1
J 0
(-1925 4125);
PAINT MONO (-1925 4125);
DISPLAY INVISIBLE (-1925 4125);
FORCEPROP 1 LASTPIN (-1775 4075) $PN 1
J 0
(-1763 4087);
DISPLAY 0.489362 (-1763 4087);
PAINT GREEN (-1763 4087);
FORCEPROP 1 LASTPIN (-1575 4075) $PN 2
J 0
(-1613 4087);
DISPLAY 0.489362 (-1613 4087);
PAINT GREEN (-1613 4087);
FORCEPROP 1 LAST TOLERANCE 1%
J 0
(-1575 4050);
DISPLAY 0.489362 (-1575 4050);
PAINT SKYBLUE (-1575 4050);
FORCEPROP 1 LAST VALUE 22
J 2
(-1775 4075);
DISPLAY 0.489362 (-1775 4075);
PAINT SKYBLUE (-1775 4075);
FORCEPROP 2 LAST CDS_LIB pure_quanta
J 0
(-1675 4075);
PAINT MONO (-1675 4075);
DISPLAY INVISIBLE (-1675 4075);
FORCEPROP 1 LAST PATH I9
J 0
(-1725 4225);
DISPLAY 0.978723 (-1725 4225);
PAINT WHITE (-1725 4225);
DISPLAY INVISIBLE (-1725 4225);
FORCEPROP 1 LAST WATTAGE 1/16W
J 2
(-1700 3925);
DISPLAY 0.978723 (-1700 3925);
PAINT SKYBLUE (-1700 3925);
DISPLAY INVISIBLE (-1700 3925);
FORCEPROP 1 LAST MATERIAL CHIP
J 0
(-1850 4050);
DISPLAY 0.489362 (-1850 4050);
PAINT SKYBLUE (-1850 4050);
DISPLAY INVISIBLE (-1850 4050);
FORCEPROP 1 LAST PART_NUMBER CS02202FB12
J 0
(-1725 4175);
DISPLAY 0.978723 (-1725 4175);
PAINT SKYBLUE (-1725 4175);
DISPLAY INVISIBLE (-1725 4175);
FORCEPROP 1 LAST PACK_TYPE 0402LF
J 0
(-1425 3925);
DISPLAY 0.978723 (-1425 3925);
PAINT SKYBLUE (-1425 3925);
DISPLAY INVISIBLE (-1425 3925);
FORCEADD OFFPAGE..1
(-8300 4125);
FORCEPROP 2 LAST $XR0 149 
J 0
(-8552 4125);
DISPLAY 0.638298 (-8552 4125);
PAINT MONO (-8552 4125);
FORCEPROP 2 LAST PATH I90
J 0
(-8500 4175);
DISPLAY 1.021277 (-8500 4175);
DISPLAY INVISIBLE (-8500 4175);
FORCEPROP 1 LAST COMMENT_BODY TRUE
J 0
(-8175 4025);
DISPLAY 0.872340 (-8175 4025);
PAINT GREEN (-8175 4025);
DISPLAY INVISIBLE (-8175 4025);
FORCEPROP 1 LAST OFFPAGE TRUE
J 0
(-7975 4000);
DISPLAY 0.872340 (-7975 4000);
PAINT GREEN (-7975 4000);
DISPLAY INVISIBLE (-7975 4000);
FORCEPROP 2 LAST CDS_LIB standard
J 0
(-8300 4125);
PAINT MONO (-8300 4125);
DISPLAY INVISIBLE (-8300 4125);
FORCEADD OFFPAGE..5
(-8300 3975);
FORCEPROP 2 LAST $XR0 149 
J 0
(-8585 3975);
DISPLAY 0.638298 (-8585 3975);
PAINT MONO (-8585 3975);
FORCEPROP 2 LAST PATH I91
J 0
(-8550 4025);
DISPLAY 1.021277 (-8550 4025);
DISPLAY INVISIBLE (-8550 4025);
FORCEPROP 1 LAST COMMENT_BODY TRUE
J 0
(-8200 3900);
DISPLAY 0.872340 (-8200 3900);
PAINT GREEN (-8200 3900);
DISPLAY INVISIBLE (-8200 3900);
FORCEPROP 1 LAST OFFPAGE TRUE
J 0
(-7975 3850);
DISPLAY 0.872340 (-7975 3850);
PAINT GREEN (-7975 3850);
DISPLAY INVISIBLE (-7975 3850);
FORCEPROP 2 LAST CDS_LIB standard
J 0
(-8300 3975);
DISPLAY INVISIBLE (-8300 3975);
FORCEADD Q_RES..1
(-8325 3350);
FORCEPROP 1 LAST LOCATION R1619
J 0
(-8375 3400);
DISPLAY 0.489362 (-8375 3400);
PAINT SKYBLUE (-8375 3400);
FORCEPROP 0 LAST $SEC 1
J 0
(-8375 3450);
PAINT MONO (-8375 3450);
DISPLAY INVISIBLE (-8375 3450);
FORCEPROP 0 LAST CDS_SEC 1
J 0
(-8375 3450);
PAINT MONO (-8375 3450);
DISPLAY INVISIBLE (-8375 3450);
FORCEPROP 1 LASTPIN (-8425 3350) $PN 1
J 0
(-8413 3362);
DISPLAY 0.489362 (-8413 3362);
PAINT GREEN (-8413 3362);
FORCEPROP 1 LASTPIN (-8225 3350) $PN 2
J 0
(-8263 3362);
DISPLAY 0.489362 (-8263 3362);
PAINT GREEN (-8263 3362);
FORCEPROP 1 LAST MATERIAL CHIP
J 0
(-8250 3325);
DISPLAY 0.489362 (-8250 3325);
PAINT SKYBLUE (-8250 3325);
FORCEPROP 1 LAST VALUE 0
J 2
(-8175 3350);
DISPLAY 0.489362 (-8175 3350);
PAINT SKYBLUE (-8175 3350);
FORCEPROP 2 LAST CDS_LIB pure_quanta
J 0
(-8325 3350);
PAINT MONO (-8325 3350);
DISPLAY INVISIBLE (-8325 3350);
FORCEPROP 1 LAST PATH I92
J 0
(-8375 3500);
DISPLAY 0.978723 (-8375 3500);
PAINT WHITE (-8375 3500);
DISPLAY INVISIBLE (-8375 3500);
FORCEPROP 1 LAST WATTAGE 1/16W
J 2
(-8350 3200);
DISPLAY 0.978723 (-8350 3200);
PAINT SKYBLUE (-8350 3200);
DISPLAY INVISIBLE (-8350 3200);
FORCEPROP 1 LAST TOLERANCE 5%
J 0
(-8325 3250);
DISPLAY 0.978723 (-8325 3250);
PAINT SKYBLUE (-8325 3250);
DISPLAY INVISIBLE (-8325 3250);
FORCEPROP 1 LAST PART_NUMBER CS00002JB38
J 0
(-8375 3450);
DISPLAY 0.978723 (-8375 3450);
PAINT SKYBLUE (-8375 3450);
DISPLAY INVISIBLE (-8375 3450);
FORCEPROP 1 LAST PACK_TYPE 0402LF
J 0
(-8075 3200);
DISPLAY 0.978723 (-8075 3200);
PAINT SKYBLUE (-8075 3200);
DISPLAY INVISIBLE (-8075 3200);
FORCEADD OFFPAGE..1
(-8725 2225);
FORCEPROP 2 LAST $XR0 148 
J 0
(-9007 2225);
DISPLAY 0.638298 (-9007 2225);
PAINT MONO (-9007 2225);
FORCEPROP 2 LAST PATH I93
J 0
(-8975 2275);
DISPLAY 1.021277 (-8975 2275);
DISPLAY INVISIBLE (-8975 2275);
FORCEPROP 1 LAST COMMENT_BODY TRUE
J 0
(-8600 2125);
DISPLAY 0.872340 (-8600 2125);
PAINT GREEN (-8600 2125);
DISPLAY INVISIBLE (-8600 2125);
FORCEPROP 1 LAST OFFPAGE TRUE
J 0
(-8400 2100);
DISPLAY 0.872340 (-8400 2100);
PAINT GREEN (-8400 2100);
DISPLAY INVISIBLE (-8400 2100);
FORCEPROP 2 LAST CDS_LIB standard
J 0
(-8725 2225);
PAINT MONO (-8725 2225);
DISPLAY INVISIBLE (-8725 2225);
FORCEADD OFFPAGE..5
(-8725 2075);
FORCEPROP 2 LAST $XR0 148 
J 0
(-8980 2075);
DISPLAY 0.638298 (-8980 2075);
PAINT MONO (-8980 2075);
FORCEPROP 2 LAST PATH I94
J 0
(-8975 2125);
DISPLAY 1.021277 (-8975 2125);
DISPLAY INVISIBLE (-8975 2125);
FORCEPROP 1 LAST COMMENT_BODY TRUE
J 0
(-8625 2000);
DISPLAY 0.872340 (-8625 2000);
PAINT GREEN (-8625 2000);
DISPLAY INVISIBLE (-8625 2000);
FORCEPROP 1 LAST OFFPAGE TRUE
J 0
(-8400 1950);
DISPLAY 0.872340 (-8400 1950);
PAINT GREEN (-8400 1950);
DISPLAY INVISIBLE (-8400 1950);
FORCEPROP 2 LAST CDS_LIB standard
J 0
(-8725 2075);
DISPLAY INVISIBLE (-8725 2075);
FORCEADD OFFPAGE..1
(-8650 600);
FORCEPROP 2 LAST $XR0 144 
J 0
(-8902 600);
DISPLAY 0.638298 (-8902 600);
PAINT MONO (-8902 600);
FORCEPROP 2 LAST PATH I95
J 0
(-8850 650);
DISPLAY 1.021277 (-8850 650);
DISPLAY INVISIBLE (-8850 650);
FORCEPROP 1 LAST COMMENT_BODY TRUE
J 0
(-8525 500);
DISPLAY 0.872340 (-8525 500);
PAINT GREEN (-8525 500);
DISPLAY INVISIBLE (-8525 500);
FORCEPROP 1 LAST OFFPAGE TRUE
J 0
(-8325 475);
DISPLAY 0.872340 (-8325 475);
PAINT GREEN (-8325 475);
DISPLAY INVISIBLE (-8325 475);
FORCEPROP 2 LAST CDS_LIB standard
J 0
(-8650 600);
PAINT MONO (-8650 600);
DISPLAY INVISIBLE (-8650 600);
FORCEADD Q_RES..1
(-1675 4175);
FORCEPROP 1 LAST LOCATION R1634
J 0
(-2050 4175);
DISPLAY 0.489362 (-2050 4175);
PAINT SKYBLUE (-2050 4175);
FORCEPROP 0 LAST $SEC 1
J 0
(-2000 4225);
DISPLAY 0.680851 (-2000 4225);
PAINT MONO (-2000 4225);
DISPLAY INVISIBLE (-2000 4225);
FORCEPROP 0 LAST CDS_SEC 1
J 0
(-2000 4225);
DISPLAY 1.021277 (-2000 4225);
DISPLAY INVISIBLE (-2000 4225);
FORCEPROP 1 LASTPIN (-1775 4175) $PN 1
J 0
(-1763 4187);
DISPLAY 0.489362 (-1763 4187);
PAINT MONO (-1763 4187);
FORCEPROP 1 LASTPIN (-1575 4175) $PN 2
J 0
(-1613 4187);
DISPLAY 0.489362 (-1613 4187);
PAINT MONO (-1613 4187);
FORCEPROP 1 LAST TOLERANCE 1%
J 0
(-1575 4150);
DISPLAY 0.489362 (-1575 4150);
PAINT SKYBLUE (-1575 4150);
FORCEPROP 1 LAST VALUE 22
J 2
(-1775 4175);
DISPLAY 0.489362 (-1775 4175);
PAINT SKYBLUE (-1775 4175);
FORCEPROP 2 LAST CDS_LIB pure_quanta
J 0
(-1675 4175);
DISPLAY INVISIBLE (-1675 4175);
FORCEPROP 1 LAST PATH I96
J 0
(-1725 4325);
DISPLAY 0.978723 (-1725 4325);
PAINT WHITE (-1725 4325);
DISPLAY INVISIBLE (-1725 4325);
FORCEPROP 1 LAST WATTAGE 1/16W
J 2
(-1700 4025);
DISPLAY 0.978723 (-1700 4025);
PAINT SKYBLUE (-1700 4025);
DISPLAY INVISIBLE (-1700 4025);
FORCEPROP 1 LAST MATERIAL CHIP
J 0
(-1850 4150);
DISPLAY 0.489362 (-1850 4150);
PAINT SKYBLUE (-1850 4150);
DISPLAY INVISIBLE (-1850 4150);
FORCEPROP 1 LAST PART_NUMBER CS02202FB12
J 0
(-1725 4275);
DISPLAY 0.978723 (-1725 4275);
PAINT SKYBLUE (-1725 4275);
DISPLAY INVISIBLE (-1725 4275);
FORCEPROP 1 LAST PACK_TYPE 0402LF
J 0
(-1425 4025);
DISPLAY 0.978723 (-1425 4025);
PAINT SKYBLUE (-1425 4025);
DISPLAY INVISIBLE (-1425 4025);
FORCEADD DNS..2
(-5375 3700);
PAINT RED (-5375 3700);
FORCEPROP 2 LAST CDS_LIB mstr_misc
J 0
(-5375 3700);
PAINT MONO (-5375 3700);
DISPLAY INVISIBLE (-5375 3700);
FORCEPROP 1 LAST COMMENT_BODY TRUE
J 0
(-5375 3700);
PAINT RED (-5375 3700);
DISPLAY INVISIBLE (-5375 3700);
FORCEADD CAD_NOTE..1
(-3250 850);
FORCEPROP 0 LAST S1 PLACE U149 AND U148 CLOSER
J 0
(-3375 725);
DISPLAY 0.808511 (-3375 725);
PAINT WHITE (-3375 725);
FORCEPROP 2 LAST CDS_LIB pure_quanta_power
J 0
(-3250 850);
DISPLAY INVISIBLE (-3250 850);
FORCEPROP 1 LAST COMMENT_BODY TRUE
J 0
(-3225 950);
DISPLAY 0.978723 (-3225 950);
DISPLAY INVISIBLE (-3225 950);
FORCEADD CAD_NOTE..1
(-5075 5250);
FORCEPROP 0 LAST S1 PLACE CAP AND RES NEAR J54
J 0
(-5200 5125);
DISPLAY 0.808511 (-5200 5125);
PAINT WHITE (-5200 5125);
FORCEPROP 2 LAST CDS_LIB pure_quanta_power
J 0
(-5075 5250);
DISPLAY INVISIBLE (-5075 5250);
FORCEPROP 1 LAST COMMENT_BODY TRUE
J 0
(-5050 5350);
DISPLAY 0.978723 (-5050 5350);
DISPLAY INVISIBLE (-5050 5350);
FORCEADD QUANTA_TITLE_BLOCK_C..1
(0 0);
FORCEPROP 0 LAST CDS_CON_LAST_MODIFIED Fri Mar 11 14:53:16 2022
J 0
(-1885 15);
DISPLAY INVISIBLE (-1885 15);
FORCEPROP 1 LAST CUSTOM_TXT_CDS <CON_LAST_MODIFIED>
J 0
(-1885 15);
DISPLAY 0.978723 (-1885 15);
FORCEPROP 2 LAST CUSTOM_TXT_CDS <XR_PAGE_TITLE>
J 0
(-7890 5250);
DISPLAY 0.638298 (-7890 5250);
PAINT PINK (-7890 5250);
DISPLAY INVISIBLE (-7890 5250);
FORCEPROP 1 LAST CUSTOM_TXT_CDS <NAME_2>
J 0
(-3175 50);
FORCEPROP 1 LAST CUSTOM_TXT_CDS <NAME_1>
J 0
(-3175 175);
FORCEPROP 1 LAST CUSTOM_TXT_CDS <Q_NUMBER>
J 0
(-1403 103);
DISPLAY 1.212766 (-1403 103);
FORCEPROP 1 LAST CUSTOM_TXT_CDS <Q_PROJ>
J 0
(-2382 102);
DISPLAY 1.212766 (-2382 102);
FORCEPROP 1 LAST CUSTOM_TXT_CDS <Q_REV>
J 0
(-184 103);
DISPLAY 1.212766 (-184 103);
FORCEPROP 1 LAST CUSTOM_TXT_CDS <CON_PAGE_NUM> OF <CON_TOTAL_PAGES>
J 0
(-446 18);
DISPLAY 0.978723 (-446 18);
FORCEPROP 1 LAST Q_TITLE JTAG - HDT & BMC MUX
J 0
(-9250 75);
DISPLAY 2.446809 (-9250 75);
PAINT GREEN (-9250 75);
FORCEPROP 1 LAST Q_DEPT BU9
J 1
(-3763 49);
DISPLAY 1.957447 (-3763 49);
PAINT GREEN (-3763 49);
FORCEPROP 2 LAST CDS_LIB pure_quanta
J 0
(0 0);
DISPLAY INVISIBLE (0 0);
FORCEPROP 1 LAST CDS_LMAN_SYM_OUTLINE -9475,6775,100,-125
J 0
(0 0);
DISPLAY 0.468085 (0 0);
PAINT GREEN (0 0);
DISPLAY INVISIBLE (0 0);
FORCEPROP 2 LAST PAGE_BORDER TRUE
J 0
(-7890 5250);
DISPLAY 0.638298 (-7890 5250);
PAINT PINK (-7890 5250);
DISPLAY INVISIBLE (-7890 5250);
FORCEPROP 1 LAST COMMENT_BODY TRUE
J 0
(12 -13);
DISPLAY 0.978723 (12 -13);
PAINT GREEN (12 -13);
DISPLAY INVISIBLE (12 -13);
FORCEPROP 2 LAST CDS_XR_PAGE_TITLE CR-149 : @T6G_MB_LIB.T6G(SCH_1):PAGE149
J 0
(-7890 5250);
DISPLAY 0.638298 (-7890 5250);
PAINT PINK (-7890 5250);
DISPLAY INVISIBLE (-7890 5250);
FORCEADD CAD_NOTE..1
(-6250 875);
FORCEPROP 0 LAST S1 PLACE U146 AND U147 CLOSER
J 0
(-6375 750);
DISPLAY 0.808511 (-6375 750);
PAINT WHITE (-6375 750);
FORCEPROP 2 LAST CDS_LIB pure_quanta_power
J 0
(-6250 875);
DISPLAY INVISIBLE (-6250 875);
FORCEPROP 1 LAST COMMENT_BODY TRUE
J 0
(-6225 975);
DISPLAY 0.978723 (-6225 975);
DISPLAY INVISIBLE (-6225 975);
WIRE 16 -1 (-2650 4450)(-2650 4425);
WIRE 16 -1 (-3675 5150)(-3675 5225);
WIRE 16 -1 (-2350 5225)(-2350 5150);
WIRE 16 -1 (-2125 5225)(-2125 5150);
WIRE 16 -1 (-2575 5225)(-2575 5150);
WIRE 16 -1 (-2800 5225)(-2800 5150);
WIRE 16 -1 (-6050 6400)(-6050 6350);
WIRE 16 -1 (-7000 5275)(-7000 5200);
WIRE 16 -1 (-800 3675)(-800 3500);
WIRE 16 -1 (-1125 3675)(-1125 3500);
WIRE 16 -1 (-1500 3675)(-1500 3500);
WIRE 16 -1 (-2650 2550)(-2650 2525);
WIRE 16 -1 (-3975 4450)(-3975 4425);
WIRE 16 -1 (-6350 4525)(-6350 4450);
WIRE 16 -1 (-3975 2300)(-3975 2275);
WIRE 16 -1 (-5375 3625)(-5375 3550);
WIRE 16 -1 (-6425 3650)(-6425 3675);
WIRE 16 -1 (-6325 2625)(-6325 2550);
WIRE 16 -1 (-7825 2700)(-7825 2675);
WIRE 16 -1 (-7475 1350)(-7475 1300);
WIRE 16 -1 (-7475 350)(-7475 500);
WIRE 16 -1 (-7600 1925)(-7400 1925);
WIRE 16 -1 (-7600 1925)(-7600 1575);
WIRE 16 -1 (-7600 1575)(-6600 1575);
WIRE 16 -1 (-6600 1575)(-3650 1575);
WIRE 16 -1 (-6600 950)(-6600 1575);
WIRE 16 -1 (-7475 950)(-6600 950);
FORCEPROP 2 LAST SIG_NAME JTAG_BMC_OE_N
J 2
(-6960 960);
DISPLAY 0.489362 (-6960 960);
FORCEPROP 2 LASTPROP $XRERR UNIQUE?
J 0
(-7200 960);
DISPLAY 0.638298 (-7200 960);
PAINT MONO (-7200 960);
DISPLAY INVISIBLE (-7200 960);
WIRE 16 -1 (-7475 950)(-7475 1100);
WIRE 16 -1 (-7475 800)(-7475 950);
WIRE 16 -1 (-4875 5700)(-1700 5700);
FORCEPROP 2 LAST SIG_NAME HDT_HDR_RESET_N
J 0
(-2135 5710);
DISPLAY 0.489362 (-2135 5710);
WIRE 16 -1 (-1700 5950)(-2800 5950);
FORCEPROP 2 LAST SIG_NAME HDT_HDR_TCK
J 0
(-2135 5960);
DISPLAY 0.489362 (-2135 5960);
WIRE 16 -1 (-2800 5950)(-2800 5425);
WIRE 16 -1 (-3650 5950)(-2800 5950);
WIRE 16 -1 (-3650 6025)(-3650 5950);
WIRE 16 -1 (-3875 5950)(-3650 5950);
WIRE 16 -1 (-3875 5900)(-3525 5900);
WIRE 16 -1 (-1700 5900)(-3525 5900);
FORCEPROP 2 LAST SIG_NAME HDT_HDR_TMS
J 0
(-2135 5910);
DISPLAY 0.489362 (-2135 5910);
WIRE 16 -1 (-3525 6025)(-3525 5900);
WIRE 16 -1 (-1700 5850)(-2575 5850);
FORCEPROP 2 LAST SIG_NAME HDT_HDR_TDI
J 0
(-2135 5860);
DISPLAY 0.489362 (-2135 5860);
WIRE 16 -1 (-2575 5850)(-2575 5425);
WIRE 16 -1 (-3400 5850)(-2575 5850);
WIRE 16 -1 (-3400 6025)(-3400 5850);
WIRE 16 -1 (-3875 5850)(-3400 5850);
WIRE 16 -1 (-7500 3825)(-7425 3825);
WIRE 16 -1 (-7500 3825)(-7500 3350);
WIRE 16 -1 (-6425 3350)(-7500 3350);
FORCEPROP 2 LAST SIG_NAME JTAG_BMC_R_D_OE
J 2
(-6960 3360);
DISPLAY 0.489362 (-6960 3360);
FORCEPROP 2 LASTPROP $XRERR UNIQUE?
J 0
(-7200 3360);
DISPLAY 0.638298 (-7200 3360);
PAINT MONO (-7200 3360);
DISPLAY INVISIBLE (-7200 3360);
WIRE 16 -1 (-7500 3350)(-8225 3350);
WIRE 16 -1 (-4325 3350)(-6425 3350);
WIRE 16 -1 (-6425 3450)(-6425 3350);
WIRE 16 -1 (-4325 3350)(-4325 3725);
WIRE 16 -1 (-4325 3725)(-3625 3725);
WIRE 16 -1 (-6600 2425)(-6550 2425);
WIRE 16 -1 (-6550 2425)(-6550 2800);
WIRE 16 -1 (-6550 2800)(-7700 2800);
WIRE 16 -1 (-7700 2175)(-7700 2800);
WIRE 16 -1 (-7700 2975)(-7700 2800);
WIRE 16 -1 (-7700 3075)(-7700 2975);
WIRE 16 -1 (-7700 2975)(-7825 2975);
WIRE 16 -1 (-7400 2175)(-7700 2175);
WIRE 16 -1 (-7825 2900)(-7825 2975);
WIRE 16 -1 (-3525 6300)(-3650 6300);
WIRE 16 -1 (-3400 6300)(-3525 6300);
WIRE 16 -1 (-3525 6225)(-3525 6300);
WIRE 16 -1 (-3650 6350)(-3650 6300);
WIRE 16 -1 (-3650 6300)(-3650 6225);
WIRE 16 -1 (-3275 6300)(-3400 6300);
WIRE 16 -1 (-3400 6225)(-3400 6300);
WIRE 16 -1 (-3275 6300)(-3150 6300);
WIRE 16 -1 (-3275 6225)(-3275 6300);
WIRE 16 -1 (-3150 6300)(-3150 6225);
WIRE 16 -1 (-2825 4425)(-2725 4425);
WIRE 16 -1 (-2725 4725)(-2725 4425);
WIRE 16 -1 (-2650 4725)(-2725 4725);
WIRE 16 -1 (-2725 4800)(-2725 4725);
WIRE 16 -1 (-2650 4650)(-2650 4725);
WIRE 16 -1 (-5375 5850)(-5475 5850);
WIRE 16 -1 (-5475 5850)(-5475 5800);
WIRE 16 -1 (-5475 5800)(-5475 5550);
WIRE 16 -1 (-5375 5800)(-5475 5800);
WIRE 16 -1 (-5375 5550)(-5475 5550);
WIRE 16 -1 (-5475 5550)(-5475 5400);
WIRE 16 -1 (-5600 5950)(-5600 5500);
WIRE 16 -1 (-5600 6150)(-5600 5950);
WIRE 16 -1 (-5375 5950)(-5600 5950);
WIRE 16 -1 (-5600 5500)(-5375 5500);
WIRE 16 -1 (-3625 3775)(-3750 3775);
WIRE 16 -1 (-3750 3825)(-3750 3775);
WIRE 16 -1 (-3750 3875)(-3750 3825);
WIRE 16 -1 (-3625 3825)(-3750 3825);
WIRE 16 -1 (-3625 3875)(-3750 3875);
WIRE 16 -1 (-3750 3925)(-3750 3875);
WIRE 16 -1 (-3750 4425)(-3750 3925);
WIRE 16 -1 (-3625 3925)(-3750 3925);
WIRE 16 -1 (-3750 4700)(-3750 4425);
WIRE 16 -1 (-3625 4425)(-3750 4425);
WIRE 16 -1 (-3750 4775)(-3750 4700);
WIRE 16 -1 (-3750 4700)(-3975 4700);
WIRE 16 -1 (-3975 4650)(-3975 4700);
WIRE 16 -1 (-2700 3550)(-2700 3675);
WIRE 16 -1 (-2825 3675)(-2700 3675);
WIRE 16 -1 (-2850 2275)(-2725 2275);
WIRE 16 -1 (-2725 2275)(-2725 2825);
WIRE 16 -1 (-2650 2825)(-2725 2825);
WIRE 16 -1 (-2725 2900)(-2725 2825);
WIRE 16 -1 (-2650 2750)(-2650 2825);
WIRE 16 -1 (-3650 1625)(-3750 1625);
WIRE 16 -1 (-3750 1675)(-3750 1625);
WIRE 16 -1 (-3650 1675)(-3750 1675);
WIRE 16 -1 (-3750 1725)(-3750 1675);
WIRE 16 -1 (-3650 1725)(-3750 1725);
WIRE 16 -1 (-3750 1775)(-3750 1725);
WIRE 16 -1 (-3750 2275)(-3750 1775);
WIRE 16 -1 (-3650 1775)(-3750 1775);
WIRE 16 -1 (-3750 2550)(-3750 2275);
WIRE 16 -1 (-3650 2275)(-3750 2275);
WIRE 16 -1 (-3750 2625)(-3750 2550);
WIRE 16 -1 (-3750 2550)(-3975 2550);
WIRE 16 -1 (-3975 2500)(-3975 2550);
WIRE 16 -1 (-2725 1400)(-2725 1525);
WIRE 16 -1 (-2850 1525)(-2725 1525);
WIRE 16 -1 (-7425 4075)(-7725 4075);
WIRE 16 -1 (-7725 4075)(-7725 4700);
WIRE 16 -1 (-7725 4700)(-6475 4700);
WIRE 16 -1 (-6475 4700)(-6475 4800);
WIRE 16 -1 (-6475 4325)(-6475 4700);
WIRE 16 -1 (-6625 4325)(-6475 4325);
WIRE 16 -1 (-6475 4275)(-6475 4325);
WIRE 16 -1 (-6350 4800)(-6475 4800);
WIRE 16 -1 (-6475 4850)(-6475 4800);
WIRE 16 -1 (-6350 4725)(-6350 4800);
WIRE 16 -1 (-6625 4275)(-6475 4275);
WIRE 16 -1 (-6600 2375)(-6450 2375);
WIRE 16 -1 (-6450 2375)(-6450 2900);
WIRE 16 -1 (-6325 2900)(-6450 2900);
WIRE 16 -1 (-6450 2950)(-6450 2900);
WIRE 16 -1 (-6325 2825)(-6325 2900);
WIRE 16 -1 (-7650 3925)(-7650 3675);
WIRE 16 -1 (-7425 3925)(-7650 3925);
WIRE 16 -1 (-7650 3675)(-7425 3675);
WIRE 16 -1 (-7650 3675)(-7650 3625);
WIRE 16 -1 (-7750 1775)(-7400 1775);
WIRE 16 -1 (-7750 2025)(-7750 1775);
WIRE 16 -1 (-7750 1775)(-7750 1725);
WIRE 16 -1 (-7400 2025)(-7750 2025);
WIRE 16 -1 (-8500 600)(-7625 600);
FORCEPROP 2 LAST SIG_NAME JTAG_BMC_OE
J 2
(-8060 610);
DISPLAY 0.489362 (-8060 610);
WIRE 16 -1 (-8500 600)(-8500 3350);
WIRE 16 -1 (-8500 600)(-8600 600);
WIRE 16 -1 (-8500 3350)(-8425 3350);
WIRE 16 -1 (-8250 4125)(-7425 4125);
FORCEPROP 2 LAST SIG_NAME HDT_HDR_TDI
J 2
(-7910 4135);
DISPLAY 0.489362 (-7910 4135);
WIRE 16 -1 (-8250 3975)(-7425 3975);
FORCEPROP 2 LAST SIG_NAME HDT_HDR_TDO
J 0
(-8160 3985);
DISPLAY 0.489362 (-8160 3985);
WIRE 16 -1 (-8675 2225)(-7400 2225);
FORCEPROP 2 LAST SIG_NAME JTAG_SCM_MUX_TDO
J 2
(-7860 2235);
DISPLAY 0.489362 (-7860 2235);
WIRE 16 -1 (-8675 2075)(-7400 2075);
FORCEPROP 2 LAST SIG_NAME JTAG_SCM_MUX_TDI
J 2
(-7860 2085);
DISPLAY 0.489362 (-7860 2085);
WIRE 16 -1 (-6625 3925)(-5825 3925);
FORCEPROP 2 LAST SIG_NAME JTAG_TDO
J 2
(-5235 3935);
DISPLAY 0.489362 (-5235 3935);
WIRE 16 -1 (-5150 3925)(-5825 3925);
WIRE 16 -1 (-5825 2025)(-5825 3925);
WIRE 16 -1 (-6600 2025)(-5825 2025);
WIRE 16 -1 (-6625 4075)(-5900 4075);
FORCEPROP 2 LAST SIG_NAME JTAG_TDI_R
J 2
(-6160 4085);
DISPLAY 0.489362 (-6160 4085);
FORCEPROP 2 LASTPROP $XRERR UNIQUE?
J 0
(-6400 4085);
DISPLAY 0.638298 (-6400 4085);
PAINT MONO (-6400 4085);
DISPLAY INVISIBLE (-6400 4085);
WIRE 16 -1 (-5900 4075)(-5825 4075);
WIRE 16 -1 (-5900 2175)(-5900 4075);
WIRE 16 -1 (-6600 2175)(-5900 2175);
WIRE 16 -1 (-5375 3825)(-5375 4075);
WIRE 16 -1 (-5150 4075)(-5375 4075);
FORCEPROP 2 LAST SIG_NAME JTAG_TDI
J 2
(-5235 4085);
DISPLAY 0.489362 (-5235 4085);
WIRE 16 -1 (-5625 4075)(-5375 4075);
WIRE 16 -1 (-7000 5750)(-6400 5750);
FORCEPROP 2 LAST SIG_NAME HDT_HDR_TRST_N
J 0
(-6925 5760);
DISPLAY 0.489362 (-6925 5760);
WIRE 16 -1 (-7100 5750)(-7000 5750);
WIRE 16 -1 (-7000 5750)(-7000 5475);
WIRE 16 -1 (-6400 5700)(-7075 5700);
FORCEPROP 2 LAST SIG_NAME CPU0_XTRIG_L6
J 0
(-6925 5710);
DISPLAY 0.489362 (-6925 5710);
WIRE 16 -1 (-6400 5650)(-7075 5650);
FORCEPROP 2 LAST SIG_NAME CPU0_XTRIG_L7
J 0
(-6925 5660);
DISPLAY 0.489362 (-6925 5660);
WIRE 16 -1 (-6400 5600)(-7075 5600);
FORCEPROP 2 LAST SIG_NAME CPU0_XTRIG_L5
J 0
(-6925 5610);
DISPLAY 0.489362 (-6925 5610);
WIRE 16 -1 (-7100 5900)(-6400 5900);
FORCEPROP 2 LAST SIG_NAME PRSNT_HDT_N
J 0
(-6925 5910);
DISPLAY 0.489362 (-6925 5910);
WIRE 16 -1 (-6200 5900)(-5375 5900);
FORCEPROP 2 LAST SIG_NAME PRSNT_HDT_R_N
J 0
(-6035 5910);
DISPLAY 0.489362 (-6035 5910);
FORCEPROP 2 LASTPROP $XRERR UNIQUE?
J 0
(-6275 5910);
DISPLAY 0.638298 (-6275 5910);
PAINT MONO (-6275 5910);
DISPLAY INVISIBLE (-6275 5910);
WIRE 16 -1 (-6200 5700)(-5375 5700);
FORCEPROP 2 LAST SIG_NAME HDT_CPU0_XTRIG_L6
J 2
(-5650 5710);
DISPLAY 0.489362 (-5650 5710);
FORCEPROP 2 LASTPROP $XRERR UNIQUE?
J 0
(-5890 5710);
DISPLAY 0.638298 (-5890 5710);
PAINT MONO (-5890 5710);
DISPLAY INVISIBLE (-5890 5710);
WIRE 16 -1 (-6200 5650)(-5375 5650);
FORCEPROP 2 LAST SIG_NAME HDT_CPU0_XTRIG_L7
J 2
(-5650 5660);
DISPLAY 0.489362 (-5650 5660);
FORCEPROP 2 LASTPROP $XRERR UNIQUE?
J 0
(-5890 5660);
DISPLAY 0.638298 (-5890 5660);
PAINT MONO (-5890 5660);
DISPLAY INVISIBLE (-5890 5660);
WIRE 16 -1 (-6200 5600)(-5375 5600);
FORCEPROP 2 LAST SIG_NAME HDT_CPU0_XTRIG_L5
J 2
(-5650 5610);
DISPLAY 0.489362 (-5650 5610);
FORCEPROP 2 LASTPROP $XRERR UNIQUE?
J 0
(-5890 5610);
DISPLAY 0.638298 (-5890 5610);
PAINT MONO (-5890 5610);
DISPLAY INVISIBLE (-5890 5610);
WIRE 16 -1 (-5375 5750)(-6050 5750);
FORCEPROP 2 LAST SIG_NAME HDT_HDR_TRST_N_R
J 2
(-5650 5760);
DISPLAY 0.489362 (-5650 5760);
FORCEPROP 2 LASTPROP $XRERR UNIQUE?
J 0
(-5890 5760);
DISPLAY 0.638298 (-5890 5760);
PAINT MONO (-5890 5760);
DISPLAY INVISIBLE (-5890 5760);
WIRE 16 -1 (-6050 6150)(-6050 5750);
WIRE 16 -1 (-6200 5750)(-6050 5750);
WIRE 16 -1 (-4075 5950)(-4875 5950);
FORCEPROP 2 LAST SIG_NAME HDT_HDR_R_TCK
J 0
(-4550 5960);
DISPLAY 0.489362 (-4550 5960);
FORCEPROP 2 LASTPROP $XRERR UNIQUE?
J 0
(-4790 5960);
DISPLAY 0.638298 (-4790 5960);
PAINT MONO (-4790 5960);
DISPLAY INVISIBLE (-4790 5960);
WIRE 16 -1 (-4875 5900)(-4075 5900);
FORCEPROP 2 LAST SIG_NAME HDT_HDR_R_TMS
J 0
(-4550 5910);
DISPLAY 0.489362 (-4550 5910);
FORCEPROP 2 LASTPROP $XRERR UNIQUE?
J 0
(-4790 5910);
DISPLAY 0.638298 (-4790 5910);
PAINT MONO (-4790 5910);
DISPLAY INVISIBLE (-4790 5910);
WIRE 16 -1 (-4875 5850)(-4075 5850);
FORCEPROP 2 LAST SIG_NAME HDT_HDR_R_TDI
J 0
(-4550 5860);
DISPLAY 0.489362 (-4550 5860);
FORCEPROP 2 LASTPROP $XRERR UNIQUE?
J 0
(-4790 5860);
DISPLAY 0.638298 (-4790 5860);
PAINT MONO (-4790 5860);
DISPLAY INVISIBLE (-4790 5860);
WIRE 16 -1 (-4875 5750)(-1700 5750);
FORCEPROP 2 LAST SIG_NAME HDT_HDR_PWROK
J 0
(-2135 5760);
DISPLAY 0.489362 (-2135 5760);
WIRE 16 -1 (-3625 4225)(-4325 4225);
FORCEPROP 2 LAST SIG_NAME HDT_HDR_TCK
J 0
(-4250 4235);
DISPLAY 0.489362 (-4250 4235);
WIRE 16 -1 (-3625 4125)(-4325 4125);
FORCEPROP 2 LAST SIG_NAME HDT_HDR_TRST_N
J 0
(-4250 4135);
DISPLAY 0.489362 (-4250 4135);
WIRE 16 -1 (-3625 4175)(-4325 4175);
FORCEPROP 2 LAST SIG_NAME HDT_HDR_TMS
J 0
(-4250 4185);
DISPLAY 0.489362 (-4250 4185);
WIRE 16 -1 (-3625 4075)(-4325 4075);
FORCEPROP 2 LAST SIG_NAME HDT_HDR_DBREQ_N
J 0
(-4250 4085);
DISPLAY 0.489362 (-4250 4085);
WIRE 16 -1 (-3650 2075)(-4325 2075);
FORCEPROP 2 LAST SIG_NAME JTAG_SCM_MUX_TCK
J 0
(-4325 2085);
DISPLAY 0.489362 (-4325 2085);
WIRE 16 -1 (-3650 2025)(-4325 2025);
FORCEPROP 2 LAST SIG_NAME JTAG_SCM_MUX_TMS
J 0
(-4325 2035);
DISPLAY 0.489362 (-4325 2035);
WIRE 16 -1 (-3650 1975)(-4325 1975);
FORCEPROP 2 LAST SIG_NAME JTAG_SCM_TRST_N
J 0
(-4325 1985);
DISPLAY 0.489362 (-4325 1985);
WIRE 16 -1 (-3650 1925)(-4325 1925);
FORCEPROP 2 LAST SIG_NAME JTAG_SCM_DBREQ_N
J 0
(-4325 1935);
DISPLAY 0.489362 (-4325 1935);
WIRE 16 -1 (-2825 4075)(-2125 4075);
FORCEPROP 2 LAST SIG_NAME JTAG_DBREQ_R_N
J 0
(-2725 4085);
DISPLAY 0.489362 (-2725 4085);
FORCEPROP 2 LASTPROP $XRERR UNIQUE?
J 0
(-2965 4085);
DISPLAY 0.638298 (-2965 4085);
PAINT MONO (-2965 4085);
DISPLAY INVISIBLE (-2965 4085);
WIRE 16 -1 (-1775 4075)(-2125 4075);
WIRE 16 -1 (-2125 1925)(-2125 4075);
WIRE 16 -1 (-2850 1925)(-2125 1925);
WIRE 16 -1 (-800 3875)(-800 4075);
WIRE 16 -1 (-575 4075)(-800 4075);
WIRE 16 -1 (-1575 4075)(-800 4075);
FORCEPROP 2 LAST SIG_NAME JTAG_DBREQ_N
J 0
(-1435 4085);
DISPLAY 0.489362 (-1435 4085);
WIRE 16 -1 (-2825 4225)(-2275 4225);
FORCEPROP 2 LAST SIG_NAME JTAG_TCK_R
J 0
(-2725 4235);
DISPLAY 0.489362 (-2725 4235);
FORCEPROP 2 LASTPROP $XRERR UNIQUE?
J 0
(-2965 4235);
DISPLAY 0.638298 (-2965 4235);
PAINT MONO (-2965 4235);
DISPLAY INVISIBLE (-2965 4235);
WIRE 16 -1 (-1775 4225)(-2275 4225);
WIRE 16 -1 (-2275 2075)(-2275 4225);
WIRE 16 -1 (-2850 2075)(-2275 2075);
WIRE 16 -1 (-2825 4125)(-2175 4125);
FORCEPROP 2 LAST SIG_NAME JTAG_TRST_R_N
J 0
(-2725 4135);
DISPLAY 0.489362 (-2725 4135);
FORCEPROP 2 LASTPROP $XRERR UNIQUE?
J 0
(-2965 4135);
DISPLAY 0.638298 (-2965 4135);
PAINT MONO (-2965 4135);
DISPLAY INVISIBLE (-2965 4135);
WIRE 16 -1 (-1775 4125)(-2175 4125);
WIRE 16 -1 (-2175 1975)(-2175 4125);
WIRE 16 -1 (-2850 1975)(-2175 1975);
WIRE 16 -1 (-1775 4175)(-2225 4175);
WIRE 16 -1 (-2225 4175)(-2825 4175);
FORCEPROP 2 LAST SIG_NAME JTAG_TMS_R
J 0
(-2725 4185);
DISPLAY 0.489362 (-2725 4185);
FORCEPROP 2 LASTPROP $XRERR UNIQUE?
J 0
(-2965 4185);
DISPLAY 0.638298 (-2965 4185);
PAINT MONO (-2965 4185);
DISPLAY INVISIBLE (-2965 4185);
WIRE 16 -1 (-2225 2025)(-2225 4175);
WIRE 16 -1 (-2850 2025)(-2225 2025);
WIRE 16 -1 (-3125 5550)(-3675 5550);
WIRE 16 -1 (-3675 5550)(-3675 5425);
WIRE 16 -1 (-4875 5550)(-3675 5550);
FORCEPROP 2 LAST SIG_NAME HDT_CPU0_HDT_CONN_TESTEN
J 0
(-4550 5560);
DISPLAY 0.489362 (-4550 5560);
FORCEPROP 2 LASTPROP $XRERR UNIQUE?
J 0
(-4790 5560);
DISPLAY 0.638298 (-4790 5560);
PAINT MONO (-4790 5560);
DISPLAY INVISIBLE (-4790 5560);
WIRE 16 -1 (-3150 6025)(-3150 5600);
WIRE 16 -1 (-3150 5600)(-3125 5600);
WIRE 16 -1 (-4875 5600)(-3150 5600);
FORCEPROP 2 LAST SIG_NAME HDT_HDR_DBREQ_R_N
J 0
(-4550 5610);
DISPLAY 0.489362 (-4550 5610);
FORCEPROP 2 LASTPROP $XRERR UNIQUE?
J 0
(-4790 5610);
DISPLAY 0.638298 (-4790 5610);
PAINT MONO (-4790 5610);
DISPLAY INVISIBLE (-4790 5610);
WIRE 16 -1 (-1675 5600)(-2350 5600);
FORCEPROP 2 LAST SIG_NAME HDT_HDR_DBREQ_N
J 0
(-2135 5610);
DISPLAY 0.489362 (-2135 5610);
WIRE 16 -1 (-2350 5600)(-2350 5425);
WIRE 16 -1 (-2925 5600)(-2350 5600);
WIRE 16 -1 (-1675 5550)(-2125 5550);
WIRE 16 -1 (-2125 5550)(-2125 5425);
WIRE 16 -1 (-2925 5550)(-2125 5550);
FORCEPROP 2 LAST SIG_NAME CPU0_HDT_CONN_TESTEN
J 0
(-2135 5560);
DISPLAY 0.489362 (-2135 5560);
WIRE 16 -1 (-3275 6025)(-3275 5800);
WIRE 16 -1 (-3275 5800)(-1700 5800);
FORCEPROP 2 LAST SIG_NAME HDT_HDR_TDO
J 0
(-2135 5810);
DISPLAY 0.489362 (-2135 5810);
WIRE 16 -1 (-4875 5800)(-3275 5800);
WIRE 16 -1 (-1575 4225)(-1500 4225);
WIRE 16 -1 (-1500 4225)(-575 4225);
FORCEPROP 2 LAST SIG_NAME JTAG_TCK
J 0
(-1435 4235);
DISPLAY 0.489362 (-1435 4235);
WIRE 16 -1 (-1500 3875)(-1500 4225);
WIRE 16 -1 (-575 4175)(-1575 4175);
FORCEPROP 2 LAST SIG_NAME JTAG_TMS
J 0
(-1435 4185);
DISPLAY 0.489362 (-1435 4185);
WIRE 16 -1 (-1575 4125)(-1125 4125);
FORCEPROP 2 LAST SIG_NAME JTAG_TRST_N
J 0
(-1435 4135);
DISPLAY 0.489362 (-1435 4135);
WIRE 16 -1 (-575 4125)(-1125 4125);
WIRE 16 -1 (-1125 3875)(-1125 4125);
DOT 1 (-7700 2800);
DOT 1 (-6050 5750);
DOT 1 (-6450 2900);
DOT 1 (-6475 4700);
DOT 1 (-1500 4225);
DOT 1 (-7500 3350);
DOT 1 (-6425 3350);
DOT 1 (-7700 2975);
DOT 1 (-7475 950);
DOT 1 (-6600 1575);
DOT 1 (-7650 3675);
DOT 1 (-8500 600);
DOT 1 (-6475 4800);
DOT 1 (-7750 1775);
DOT 1 (-5900 4075);
DOT 1 (-5825 3925);
DOT 1 (-5375 4075);
DOT 1 (-1125 4125);
DOT 1 (-6475 4325);
DOT 1 (-3275 6300);
DOT 1 (-3400 6300);
DOT 1 (-3525 6300);
DOT 1 (-3650 6300);
DOT 1 (-3275 5800);
DOT 1 (-3400 5850);
DOT 1 (-3525 5900);
DOT 1 (-3650 5950);
DOT 1 (-800 4075);
DOT 1 (-3675 5550);
DOT 1 (-2800 5950);
DOT 1 (-2350 5600);
DOT 1 (-2125 5550);
DOT 1 (-2575 5850);
DOT 1 (-3150 5600);
DOT 1 (-2225 4175);
DOT 1 (-2275 4225);
DOT 1 (-2175 4125);
DOT 1 (-2125 4075);
DOT 1 (-2725 2825);
DOT 1 (-2725 4725);
DOT 1 (-3750 4700);
DOT 1 (-3750 1775);
DOT 1 (-3750 2550);
DOT 1 (-3750 1725);
DOT 1 (-3750 1675);
DOT 1 (-3750 3925);
DOT 1 (-3750 3875);
DOT 1 (-3750 3825);
DOT 1 (-3750 4425);
DOT 1 (-3750 2275);
DOT 1 (-5475 5800);
DOT 1 (-5600 5950);
DOT 1 (-7000 5750);
DOT 1 (-5475 5550);
FORCENOTE
BMC 
(-9025 2450) 0;
DISPLAY LEFT (-9025 2450);
DISPLAY 2.510638 (-9025 2450);
PAINT WHITE (-9025 2450);
FORCENOTE
L:HDT
(-9150 1000) 0;
DISPLAY LEFT (-9150 1000);
DISPLAY 2.510638 (-9150 1000);
PAINT WHITE (-9150 1000);
FORCENOTE
H:BMC
(-9150 775) 0;
DISPLAY LEFT (-9150 775);
DISPLAY 2.510638 (-9150 775);
PAINT WHITE (-9150 775);
FORCENOTE
HDT
(-8925 4350) 0;
DISPLAY LEFT (-8925 4350);
DISPLAY 2.510638 (-8925 4350);
PAINT WHITE (-8925 4350);
FORCENOTE
TO JTAG BUF
(-1475 4350) 0;
DISPLAY LEFT (-1475 4350);
DISPLAY 2.510638 (-1475 4350);
PAINT WHITE (-1475 4350);
QUIT
